FILE_TYPE = MACRO_DRAWING;
SET COLOR_WIRE YELLOW;
SET COLOR_PROP MONO;
SET COLOR_DOT WHITE;
SET COLOR_ARC YELLOW;
SET COLOR_BODY GREEN;
SET COLOR_NOTE MONO;
SET PROP_DISPLAY VALUE;
SET PAGE_NUMBER P27;
FORCEADD OFFPAGE..5
(-6450 500);
FORCEPROP 2 LAST $XR0 51 
J 0
(-6674 500);
DISPLAY 0.638298 (-6674 500);
PAINT MONO (-6674 500);
FORCEPROP 2 LAST $XR1 52 
J 0
(-6764 500);
DISPLAY 0.638298 (-6764 500);
PAINT MONO (-6764 500);
FORCEPROP 2 LAST CDS_LIB mstr_standard
J 0
(-6450 500);
PAINT MONO (-6450 500);
DISPLAY INVISIBLE (-6450 500);
FORCEPROP 1 LAST OFFPAGE TRUE
J 0
(-6125 375);
DISPLAY 1.170213 (-6125 375);
PAINT GREEN (-6125 375);
DISPLAY INVISIBLE (-6125 375);
FORCEPROP 1 LAST COMMENT_BODY TRUE
J 0
(-6350 425);
DISPLAY 1.170213 (-6350 425);
PAINT GREEN (-6350 425);
DISPLAY INVISIBLE (-6350 425);
FORCEPROP 2 LAST PATH I1
J 0
(-6400 575);
DISPLAY 1.021277 (-6400 575);
PAINT ORANGE (-6400 575);
DISPLAY INVISIBLE (-6400 575);
FORCEADD TAP..6
(-5575 850);
FORCEPROP 3 LASTPIN (-5525 850) SIG_NAME M_E_CLK_DP<1>
J 0
(-5515 860);
DISPLAY 0.659574 (-5515 860);
PAINT MONO (-5515 860);
DISPLAY INVISIBLE (-5515 860);
FORCEPROP 1 LASTPIN (-5525 850) BN 1
J 0
(-5577 858);
DISPLAY 0.617021 (-5577 858);
PAINT PINK (-5577 858);
FORCEPROP 2 LAST CDS_LIB mstr_standard
J 0
(-5575 850);
PAINT MONO (-5575 850);
DISPLAY INVISIBLE (-5575 850);
FORCEPROP 1 LAST BODY_TYPE PLUMBING
J 0
(-5575 800);
DISPLAY 1.595745 (-5575 800);
PAINT GREEN (-5575 800);
DISPLAY INVISIBLE (-5575 800);
FORCEPROP 1 LAST HDL_TAP TRUE
J 0
(-5250 725);
DISPLAY 1.595745 (-5250 725);
PAINT GREEN (-5250 725);
DISPLAY INVISIBLE (-5250 725);
FORCEPROP 1 LAST PATH I10
J 0
(-5577 850);
DISPLAY 0.872340 (-5577 850);
PAINT GREEN (-5577 850);
DISPLAY INVISIBLE (-5577 850);
FORCEADD TAP..6
R 2
(-2850 1400);
FORCEPROP 3 LASTPIN (-2900 1400) SIG_NAME M_E_ODT<0>
J 0
(-2890 1410);
DISPLAY 0.659574 (-2890 1410);
PAINT MONO (-2890 1410);
DISPLAY INVISIBLE (-2890 1410);
FORCEPROP 1 LASTPIN (-2900 1400) BN 0
J 2
(-2848 1408);
DISPLAY 0.617021 (-2848 1408);
PAINT PINK (-2848 1408);
FORCEPROP 2 LAST CDS_LIB mstr_standard
J 0
(-2850 1400);
PAINT MONO (-2850 1400);
DISPLAY INVISIBLE (-2850 1400);
FORCEPROP 1 LAST BODY_TYPE PLUMBING
J 2
(-2850 1350);
DISPLAY 1.595745 (-2850 1350);
PAINT GREEN (-2850 1350);
DISPLAY INVISIBLE (-2850 1350);
FORCEPROP 1 LAST HDL_TAP TRUE
J 2
(-3175 1275);
DISPLAY 1.595745 (-3175 1275);
PAINT GREEN (-3175 1275);
DISPLAY INVISIBLE (-3175 1275);
FORCEPROP 1 LAST PATH I100
J 2
(-2848 1400);
DISPLAY 0.872340 (-2848 1400);
PAINT GREEN (-2848 1400);
DISPLAY INVISIBLE (-2848 1400);
FORCEADD TAP..6
R 2
(-2850 1550);
FORCEPROP 3 LASTPIN (-2900 1550) SIG_NAME M_E_ODT<3>
J 0
(-2890 1560);
DISPLAY 0.659574 (-2890 1560);
PAINT MONO (-2890 1560);
DISPLAY INVISIBLE (-2890 1560);
FORCEPROP 1 LASTPIN (-2900 1550) BN 3
J 2
(-2848 1558);
DISPLAY 0.617021 (-2848 1558);
PAINT PINK (-2848 1558);
FORCEPROP 2 LAST CDS_LIB mstr_standard
J 0
(-2850 1550);
PAINT MONO (-2850 1550);
DISPLAY INVISIBLE (-2850 1550);
FORCEPROP 1 LAST BODY_TYPE PLUMBING
J 2
(-2850 1500);
DISPLAY 1.595745 (-2850 1500);
PAINT GREEN (-2850 1500);
DISPLAY INVISIBLE (-2850 1500);
FORCEPROP 1 LAST HDL_TAP TRUE
J 2
(-3175 1425);
DISPLAY 1.595745 (-3175 1425);
PAINT GREEN (-3175 1425);
DISPLAY INVISIBLE (-3175 1425);
FORCEPROP 1 LAST PATH I101
J 2
(-2848 1550);
DISPLAY 0.872340 (-2848 1550);
PAINT GREEN (-2848 1550);
DISPLAY INVISIBLE (-2848 1550);
FORCEADD TAP..6
R 2
(-2850 1500);
FORCEPROP 3 LASTPIN (-2900 1500) SIG_NAME M_E_ODT<2>
J 0
(-2890 1510);
DISPLAY 0.659574 (-2890 1510);
PAINT MONO (-2890 1510);
DISPLAY INVISIBLE (-2890 1510);
FORCEPROP 1 LASTPIN (-2900 1500) BN 2
J 2
(-2848 1508);
DISPLAY 0.617021 (-2848 1508);
PAINT PINK (-2848 1508);
FORCEPROP 2 LAST CDS_LIB mstr_standard
J 0
(-2850 1500);
PAINT MONO (-2850 1500);
DISPLAY INVISIBLE (-2850 1500);
FORCEPROP 1 LAST BODY_TYPE PLUMBING
J 2
(-2850 1450);
DISPLAY 1.595745 (-2850 1450);
PAINT GREEN (-2850 1450);
DISPLAY INVISIBLE (-2850 1450);
FORCEPROP 1 LAST HDL_TAP TRUE
J 2
(-3175 1375);
DISPLAY 1.595745 (-3175 1375);
PAINT GREEN (-3175 1375);
DISPLAY INVISIBLE (-3175 1375);
FORCEPROP 1 LAST PATH I102
J 2
(-2848 1500);
DISPLAY 0.872340 (-2848 1500);
PAINT GREEN (-2848 1500);
DISPLAY INVISIBLE (-2848 1500);
FORCEADD TAP..6
R 2
(-2850 1650);
FORCEPROP 3 LASTPIN (-2900 1650) SIG_NAME M_E_CKE<0>
J 0
(-2890 1660);
DISPLAY 0.659574 (-2890 1660);
PAINT MONO (-2890 1660);
DISPLAY INVISIBLE (-2890 1660);
FORCEPROP 1 LASTPIN (-2900 1650) BN 0
J 2
(-2848 1658);
DISPLAY 0.617021 (-2848 1658);
PAINT PINK (-2848 1658);
FORCEPROP 2 LAST CDS_LIB mstr_standard
J 0
(-2850 1650);
PAINT MONO (-2850 1650);
DISPLAY INVISIBLE (-2850 1650);
FORCEPROP 1 LAST BODY_TYPE PLUMBING
J 2
(-2850 1600);
DISPLAY 1.595745 (-2850 1600);
PAINT GREEN (-2850 1600);
DISPLAY INVISIBLE (-2850 1600);
FORCEPROP 1 LAST HDL_TAP TRUE
J 2
(-3175 1525);
DISPLAY 1.595745 (-3175 1525);
PAINT GREEN (-3175 1525);
DISPLAY INVISIBLE (-3175 1525);
FORCEPROP 1 LAST PATH I103
J 2
(-2848 1650);
DISPLAY 0.872340 (-2848 1650);
PAINT GREEN (-2848 1650);
DISPLAY INVISIBLE (-2848 1650);
FORCEADD TAP..6
R 2
(-2850 1700);
FORCEPROP 3 LASTPIN (-2900 1700) SIG_NAME M_E_CKE<1>
J 0
(-2890 1710);
DISPLAY 0.659574 (-2890 1710);
PAINT MONO (-2890 1710);
DISPLAY INVISIBLE (-2890 1710);
FORCEPROP 1 LASTPIN (-2900 1700) BN 1
J 2
(-2848 1708);
DISPLAY 0.617021 (-2848 1708);
PAINT PINK (-2848 1708);
FORCEPROP 2 LAST CDS_LIB mstr_standard
J 0
(-2850 1700);
PAINT MONO (-2850 1700);
DISPLAY INVISIBLE (-2850 1700);
FORCEPROP 1 LAST BODY_TYPE PLUMBING
J 2
(-2850 1650);
DISPLAY 1.595745 (-2850 1650);
PAINT GREEN (-2850 1650);
DISPLAY INVISIBLE (-2850 1650);
FORCEPROP 1 LAST HDL_TAP TRUE
J 2
(-3175 1575);
DISPLAY 1.595745 (-3175 1575);
PAINT GREEN (-3175 1575);
DISPLAY INVISIBLE (-3175 1575);
FORCEPROP 1 LAST PATH I104
J 2
(-2848 1700);
DISPLAY 0.872340 (-2848 1700);
PAINT GREEN (-2848 1700);
DISPLAY INVISIBLE (-2848 1700);
FORCEADD TAP..6
R 2
(-2850 1800);
FORCEPROP 3 LASTPIN (-2900 1800) SIG_NAME M_E_CKE<3>
J 0
(-2890 1810);
DISPLAY 0.659574 (-2890 1810);
PAINT MONO (-2890 1810);
DISPLAY INVISIBLE (-2890 1810);
FORCEPROP 1 LASTPIN (-2900 1800) BN 3
J 2
(-2848 1808);
DISPLAY 0.617021 (-2848 1808);
PAINT PINK (-2848 1808);
FORCEPROP 2 LAST CDS_LIB mstr_standard
J 0
(-2850 1800);
PAINT MONO (-2850 1800);
DISPLAY INVISIBLE (-2850 1800);
FORCEPROP 1 LAST BODY_TYPE PLUMBING
J 2
(-2850 1750);
DISPLAY 1.595745 (-2850 1750);
PAINT GREEN (-2850 1750);
DISPLAY INVISIBLE (-2850 1750);
FORCEPROP 1 LAST HDL_TAP TRUE
J 2
(-3175 1675);
DISPLAY 1.595745 (-3175 1675);
PAINT GREEN (-3175 1675);
DISPLAY INVISIBLE (-3175 1675);
FORCEPROP 1 LAST PATH I105
J 2
(-2848 1800);
DISPLAY 0.872340 (-2848 1800);
PAINT GREEN (-2848 1800);
DISPLAY INVISIBLE (-2848 1800);
FORCEADD TAP..6
R 2
(-2850 1750);
FORCEPROP 3 LASTPIN (-2900 1750) SIG_NAME M_E_CKE<2>
J 0
(-2890 1760);
DISPLAY 0.659574 (-2890 1760);
PAINT MONO (-2890 1760);
DISPLAY INVISIBLE (-2890 1760);
FORCEPROP 1 LASTPIN (-2900 1750) BN 2
J 2
(-2848 1758);
DISPLAY 0.617021 (-2848 1758);
PAINT PINK (-2848 1758);
FORCEPROP 2 LAST CDS_LIB mstr_standard
J 0
(-2850 1750);
PAINT MONO (-2850 1750);
DISPLAY INVISIBLE (-2850 1750);
FORCEPROP 1 LAST BODY_TYPE PLUMBING
J 2
(-2850 1700);
DISPLAY 1.595745 (-2850 1700);
PAINT GREEN (-2850 1700);
DISPLAY INVISIBLE (-2850 1700);
FORCEPROP 1 LAST HDL_TAP TRUE
J 2
(-3175 1625);
DISPLAY 1.595745 (-3175 1625);
PAINT GREEN (-3175 1625);
DISPLAY INVISIBLE (-3175 1625);
FORCEPROP 1 LAST PATH I106
J 2
(-2848 1750);
DISPLAY 0.872340 (-2848 1750);
PAINT GREEN (-2848 1750);
DISPLAY INVISIBLE (-2848 1750);
FORCEADD TAP..6
R 2
(-2850 1900);
FORCEPROP 3 LASTPIN (-2900 1900) SIG_NAME M_E_MA<0>
J 0
(-2890 1910);
DISPLAY 0.659574 (-2890 1910);
PAINT MONO (-2890 1910);
DISPLAY INVISIBLE (-2890 1910);
FORCEPROP 1 LASTPIN (-2900 1900) BN 0
J 2
(-2848 1908);
DISPLAY 0.617021 (-2848 1908);
PAINT PINK (-2848 1908);
FORCEPROP 2 LAST CDS_LIB mstr_standard
J 0
(-2850 1900);
PAINT MONO (-2850 1900);
DISPLAY INVISIBLE (-2850 1900);
FORCEPROP 1 LAST BODY_TYPE PLUMBING
J 2
(-2850 1850);
DISPLAY 1.595745 (-2850 1850);
PAINT GREEN (-2850 1850);
DISPLAY INVISIBLE (-2850 1850);
FORCEPROP 1 LAST HDL_TAP TRUE
J 2
(-3175 1775);
DISPLAY 1.595745 (-3175 1775);
PAINT GREEN (-3175 1775);
DISPLAY INVISIBLE (-3175 1775);
FORCEPROP 1 LAST PATH I107
J 2
(-2848 1900);
DISPLAY 0.872340 (-2848 1900);
PAINT GREEN (-2848 1900);
DISPLAY INVISIBLE (-2848 1900);
FORCEADD TAP..6
R 2
(-2850 1950);
FORCEPROP 3 LASTPIN (-2900 1950) SIG_NAME M_E_MA<1>
J 0
(-2890 1960);
DISPLAY 0.659574 (-2890 1960);
PAINT MONO (-2890 1960);
DISPLAY INVISIBLE (-2890 1960);
FORCEPROP 1 LASTPIN (-2900 1950) BN 1
J 2
(-2848 1958);
DISPLAY 0.617021 (-2848 1958);
PAINT PINK (-2848 1958);
FORCEPROP 2 LAST CDS_LIB mstr_standard
J 0
(-2850 1950);
PAINT MONO (-2850 1950);
DISPLAY INVISIBLE (-2850 1950);
FORCEPROP 1 LAST BODY_TYPE PLUMBING
J 2
(-2850 1900);
DISPLAY 1.595745 (-2850 1900);
PAINT GREEN (-2850 1900);
DISPLAY INVISIBLE (-2850 1900);
FORCEPROP 1 LAST HDL_TAP TRUE
J 2
(-3175 1825);
DISPLAY 1.595745 (-3175 1825);
PAINT GREEN (-3175 1825);
DISPLAY INVISIBLE (-3175 1825);
FORCEPROP 1 LAST PATH I108
J 2
(-2848 1950);
DISPLAY 0.872340 (-2848 1950);
PAINT GREEN (-2848 1950);
DISPLAY INVISIBLE (-2848 1950);
FORCEADD TAP..6
R 2
(-2850 2050);
FORCEPROP 3 LASTPIN (-2900 2050) SIG_NAME M_E_MA<3>
J 0
(-2890 2060);
DISPLAY 0.659574 (-2890 2060);
PAINT MONO (-2890 2060);
DISPLAY INVISIBLE (-2890 2060);
FORCEPROP 1 LASTPIN (-2900 2050) BN 3
J 2
(-2848 2058);
DISPLAY 0.617021 (-2848 2058);
PAINT PINK (-2848 2058);
FORCEPROP 2 LAST CDS_LIB mstr_standard
J 0
(-2850 2050);
PAINT MONO (-2850 2050);
DISPLAY INVISIBLE (-2850 2050);
FORCEPROP 1 LAST BODY_TYPE PLUMBING
J 2
(-2850 2000);
DISPLAY 1.595745 (-2850 2000);
PAINT GREEN (-2850 2000);
DISPLAY INVISIBLE (-2850 2000);
FORCEPROP 1 LAST HDL_TAP TRUE
J 2
(-3175 1925);
DISPLAY 1.595745 (-3175 1925);
PAINT GREEN (-3175 1925);
DISPLAY INVISIBLE (-3175 1925);
FORCEPROP 1 LAST PATH I109
J 2
(-2848 2050);
DISPLAY 0.872340 (-2848 2050);
PAINT GREEN (-2848 2050);
DISPLAY INVISIBLE (-2848 2050);
FORCEADD TAP..6
(-5575 900);
FORCEPROP 3 LASTPIN (-5525 900) SIG_NAME M_E_CLK_DP<2>
J 0
(-5515 910);
DISPLAY 0.659574 (-5515 910);
PAINT MONO (-5515 910);
DISPLAY INVISIBLE (-5515 910);
FORCEPROP 1 LASTPIN (-5525 900) BN 2
J 0
(-5577 908);
DISPLAY 0.617021 (-5577 908);
PAINT PINK (-5577 908);
FORCEPROP 2 LAST CDS_LIB mstr_standard
J 0
(-5575 900);
PAINT MONO (-5575 900);
DISPLAY INVISIBLE (-5575 900);
FORCEPROP 1 LAST BODY_TYPE PLUMBING
J 0
(-5575 850);
DISPLAY 1.595745 (-5575 850);
PAINT GREEN (-5575 850);
DISPLAY INVISIBLE (-5575 850);
FORCEPROP 1 LAST HDL_TAP TRUE
J 0
(-5250 775);
DISPLAY 1.595745 (-5250 775);
PAINT GREEN (-5250 775);
DISPLAY INVISIBLE (-5250 775);
FORCEPROP 1 LAST PATH I11
J 0
(-5577 900);
DISPLAY 0.872340 (-5577 900);
PAINT GREEN (-5577 900);
DISPLAY INVISIBLE (-5577 900);
FORCEADD TAP..6
R 2
(-2850 2000);
FORCEPROP 3 LASTPIN (-2900 2000) SIG_NAME M_E_MA<2>
J 0
(-2890 2010);
DISPLAY 0.659574 (-2890 2010);
PAINT MONO (-2890 2010);
DISPLAY INVISIBLE (-2890 2010);
FORCEPROP 1 LASTPIN (-2900 2000) BN 2
J 2
(-2848 2008);
DISPLAY 0.617021 (-2848 2008);
PAINT PINK (-2848 2008);
FORCEPROP 2 LAST CDS_LIB mstr_standard
J 0
(-2850 2000);
PAINT MONO (-2850 2000);
DISPLAY INVISIBLE (-2850 2000);
FORCEPROP 1 LAST BODY_TYPE PLUMBING
J 2
(-2850 1950);
DISPLAY 1.595745 (-2850 1950);
PAINT GREEN (-2850 1950);
DISPLAY INVISIBLE (-2850 1950);
FORCEPROP 1 LAST HDL_TAP TRUE
J 2
(-3175 1875);
DISPLAY 1.595745 (-3175 1875);
PAINT GREEN (-3175 1875);
DISPLAY INVISIBLE (-3175 1875);
FORCEPROP 1 LAST PATH I110
J 2
(-2848 2000);
DISPLAY 0.872340 (-2848 2000);
PAINT GREEN (-2848 2000);
DISPLAY INVISIBLE (-2848 2000);
FORCEADD TAP..6
R 2
(-2850 2100);
FORCEPROP 3 LASTPIN (-2900 2100) SIG_NAME M_E_MA<4>
J 0
(-2890 2110);
DISPLAY 0.659574 (-2890 2110);
PAINT MONO (-2890 2110);
DISPLAY INVISIBLE (-2890 2110);
FORCEPROP 1 LASTPIN (-2900 2100) BN 4
J 2
(-2848 2108);
DISPLAY 0.617021 (-2848 2108);
PAINT PINK (-2848 2108);
FORCEPROP 2 LAST CDS_LIB mstr_standard
J 0
(-2850 2100);
PAINT MONO (-2850 2100);
DISPLAY INVISIBLE (-2850 2100);
FORCEPROP 1 LAST BODY_TYPE PLUMBING
J 2
(-2850 2050);
DISPLAY 1.595745 (-2850 2050);
PAINT GREEN (-2850 2050);
DISPLAY INVISIBLE (-2850 2050);
FORCEPROP 1 LAST HDL_TAP TRUE
J 2
(-3175 1975);
DISPLAY 1.595745 (-3175 1975);
PAINT GREEN (-3175 1975);
DISPLAY INVISIBLE (-3175 1975);
FORCEPROP 1 LAST PATH I111
J 2
(-2848 2100);
DISPLAY 0.872340 (-2848 2100);
PAINT GREEN (-2848 2100);
DISPLAY INVISIBLE (-2848 2100);
FORCEADD TAP..6
R 2
(-2850 2150);
FORCEPROP 3 LASTPIN (-2900 2150) SIG_NAME M_E_MA<5>
J 0
(-2890 2160);
DISPLAY 0.659574 (-2890 2160);
PAINT MONO (-2890 2160);
DISPLAY INVISIBLE (-2890 2160);
FORCEPROP 1 LASTPIN (-2900 2150) BN 5
J 2
(-2848 2158);
DISPLAY 0.617021 (-2848 2158);
PAINT PINK (-2848 2158);
FORCEPROP 2 LAST CDS_LIB mstr_standard
J 0
(-2850 2150);
PAINT MONO (-2850 2150);
DISPLAY INVISIBLE (-2850 2150);
FORCEPROP 1 LAST BODY_TYPE PLUMBING
J 2
(-2850 2100);
DISPLAY 1.595745 (-2850 2100);
PAINT GREEN (-2850 2100);
DISPLAY INVISIBLE (-2850 2100);
FORCEPROP 1 LAST HDL_TAP TRUE
J 2
(-3175 2025);
DISPLAY 1.595745 (-3175 2025);
PAINT GREEN (-3175 2025);
DISPLAY INVISIBLE (-3175 2025);
FORCEPROP 1 LAST PATH I112
J 2
(-2848 2150);
DISPLAY 0.872340 (-2848 2150);
PAINT GREEN (-2848 2150);
DISPLAY INVISIBLE (-2848 2150);
FORCEADD TAP..6
R 2
(-2850 2200);
FORCEPROP 3 LASTPIN (-2900 2200) SIG_NAME M_E_MA<6>
J 0
(-2890 2210);
DISPLAY 0.659574 (-2890 2210);
PAINT MONO (-2890 2210);
DISPLAY INVISIBLE (-2890 2210);
FORCEPROP 1 LASTPIN (-2900 2200) BN 6
J 2
(-2848 2208);
DISPLAY 0.617021 (-2848 2208);
PAINT PINK (-2848 2208);
FORCEPROP 2 LAST CDS_LIB mstr_standard
J 0
(-2850 2200);
PAINT MONO (-2850 2200);
DISPLAY INVISIBLE (-2850 2200);
FORCEPROP 1 LAST BODY_TYPE PLUMBING
J 2
(-2850 2150);
DISPLAY 1.595745 (-2850 2150);
PAINT GREEN (-2850 2150);
DISPLAY INVISIBLE (-2850 2150);
FORCEPROP 1 LAST HDL_TAP TRUE
J 2
(-3175 2075);
DISPLAY 1.595745 (-3175 2075);
PAINT GREEN (-3175 2075);
DISPLAY INVISIBLE (-3175 2075);
FORCEPROP 1 LAST PATH I113
J 2
(-2848 2200);
DISPLAY 0.872340 (-2848 2200);
PAINT GREEN (-2848 2200);
DISPLAY INVISIBLE (-2848 2200);
FORCEADD TAP..6
R 2
(-2850 2350);
FORCEPROP 3 LASTPIN (-2900 2350) SIG_NAME M_E_MA<9>
J 0
(-2890 2360);
DISPLAY 0.659574 (-2890 2360);
PAINT MONO (-2890 2360);
DISPLAY INVISIBLE (-2890 2360);
FORCEPROP 1 LASTPIN (-2900 2350) BN 9
J 2
(-2848 2358);
DISPLAY 0.617021 (-2848 2358);
PAINT PINK (-2848 2358);
FORCEPROP 2 LAST CDS_LIB mstr_standard
J 0
(-2850 2350);
PAINT MONO (-2850 2350);
DISPLAY INVISIBLE (-2850 2350);
FORCEPROP 1 LAST BODY_TYPE PLUMBING
J 2
(-2850 2300);
DISPLAY 1.595745 (-2850 2300);
PAINT GREEN (-2850 2300);
DISPLAY INVISIBLE (-2850 2300);
FORCEPROP 1 LAST HDL_TAP TRUE
J 2
(-3175 2225);
DISPLAY 1.595745 (-3175 2225);
PAINT GREEN (-3175 2225);
DISPLAY INVISIBLE (-3175 2225);
FORCEPROP 1 LAST PATH I114
J 2
(-2848 2350);
DISPLAY 0.872340 (-2848 2350);
PAINT GREEN (-2848 2350);
DISPLAY INVISIBLE (-2848 2350);
FORCEADD TAP..6
R 2
(-2850 2300);
FORCEPROP 3 LASTPIN (-2900 2300) SIG_NAME M_E_MA<8>
J 0
(-2890 2310);
DISPLAY 0.659574 (-2890 2310);
PAINT MONO (-2890 2310);
DISPLAY INVISIBLE (-2890 2310);
FORCEPROP 1 LASTPIN (-2900 2300) BN 8
J 2
(-2848 2308);
DISPLAY 0.617021 (-2848 2308);
PAINT PINK (-2848 2308);
FORCEPROP 2 LAST CDS_LIB mstr_standard
J 0
(-2850 2300);
PAINT MONO (-2850 2300);
DISPLAY INVISIBLE (-2850 2300);
FORCEPROP 1 LAST BODY_TYPE PLUMBING
J 2
(-2850 2250);
DISPLAY 1.595745 (-2850 2250);
PAINT GREEN (-2850 2250);
DISPLAY INVISIBLE (-2850 2250);
FORCEPROP 1 LAST HDL_TAP TRUE
J 2
(-3175 2175);
DISPLAY 1.595745 (-3175 2175);
PAINT GREEN (-3175 2175);
DISPLAY INVISIBLE (-3175 2175);
FORCEPROP 1 LAST PATH I115
J 2
(-2848 2300);
DISPLAY 0.872340 (-2848 2300);
PAINT GREEN (-2848 2300);
DISPLAY INVISIBLE (-2848 2300);
FORCEADD TAP..6
R 2
(-2850 2250);
FORCEPROP 3 LASTPIN (-2900 2250) SIG_NAME M_E_MA<7>
J 0
(-2890 2260);
DISPLAY 0.659574 (-2890 2260);
PAINT MONO (-2890 2260);
DISPLAY INVISIBLE (-2890 2260);
FORCEPROP 1 LASTPIN (-2900 2250) BN 7
J 2
(-2848 2258);
DISPLAY 0.617021 (-2848 2258);
PAINT PINK (-2848 2258);
FORCEPROP 2 LAST CDS_LIB mstr_standard
J 0
(-2850 2250);
PAINT MONO (-2850 2250);
DISPLAY INVISIBLE (-2850 2250);
FORCEPROP 1 LAST BODY_TYPE PLUMBING
J 2
(-2850 2200);
DISPLAY 1.595745 (-2850 2200);
PAINT GREEN (-2850 2200);
DISPLAY INVISIBLE (-2850 2200);
FORCEPROP 1 LAST HDL_TAP TRUE
J 2
(-3175 2125);
DISPLAY 1.595745 (-3175 2125);
PAINT GREEN (-3175 2125);
DISPLAY INVISIBLE (-3175 2125);
FORCEPROP 1 LAST PATH I116
J 2
(-2848 2250);
DISPLAY 0.872340 (-2848 2250);
PAINT GREEN (-2848 2250);
DISPLAY INVISIBLE (-2848 2250);
FORCEADD TAP..6
R 2
(-2850 2450);
FORCEPROP 3 LASTPIN (-2900 2450) SIG_NAME M_E_MA<11>
J 0
(-2890 2460);
DISPLAY 0.659574 (-2890 2460);
PAINT MONO (-2890 2460);
DISPLAY INVISIBLE (-2890 2460);
FORCEPROP 1 LASTPIN (-2900 2450) BN 11
J 2
(-2848 2458);
DISPLAY 0.617021 (-2848 2458);
PAINT PINK (-2848 2458);
FORCEPROP 2 LAST CDS_LIB mstr_standard
J 0
(-2850 2450);
PAINT MONO (-2850 2450);
DISPLAY INVISIBLE (-2850 2450);
FORCEPROP 1 LAST BODY_TYPE PLUMBING
J 2
(-2850 2400);
DISPLAY 1.595745 (-2850 2400);
PAINT GREEN (-2850 2400);
DISPLAY INVISIBLE (-2850 2400);
FORCEPROP 1 LAST HDL_TAP TRUE
J 2
(-3175 2325);
DISPLAY 1.595745 (-3175 2325);
PAINT GREEN (-3175 2325);
DISPLAY INVISIBLE (-3175 2325);
FORCEPROP 1 LAST PATH I117
J 2
(-2848 2450);
DISPLAY 0.872340 (-2848 2450);
PAINT GREEN (-2848 2450);
DISPLAY INVISIBLE (-2848 2450);
FORCEADD TAP..6
R 2
(-2850 2400);
FORCEPROP 3 LASTPIN (-2900 2400) SIG_NAME M_E_MA<10>
J 0
(-2890 2410);
DISPLAY 0.659574 (-2890 2410);
PAINT MONO (-2890 2410);
DISPLAY INVISIBLE (-2890 2410);
FORCEPROP 1 LASTPIN (-2900 2400) BN 10
J 2
(-2848 2408);
DISPLAY 0.617021 (-2848 2408);
PAINT PINK (-2848 2408);
FORCEPROP 2 LAST CDS_LIB mstr_standard
J 0
(-2850 2400);
PAINT MONO (-2850 2400);
DISPLAY INVISIBLE (-2850 2400);
FORCEPROP 1 LAST BODY_TYPE PLUMBING
J 2
(-2850 2350);
DISPLAY 1.595745 (-2850 2350);
PAINT GREEN (-2850 2350);
DISPLAY INVISIBLE (-2850 2350);
FORCEPROP 1 LAST HDL_TAP TRUE
J 2
(-3175 2275);
DISPLAY 1.595745 (-3175 2275);
PAINT GREEN (-3175 2275);
DISPLAY INVISIBLE (-3175 2275);
FORCEPROP 1 LAST PATH I118
J 2
(-2848 2400);
DISPLAY 0.872340 (-2848 2400);
PAINT GREEN (-2848 2400);
DISPLAY INVISIBLE (-2848 2400);
FORCEADD TAP..6
R 2
(-2850 2500);
FORCEPROP 3 LASTPIN (-2900 2500) SIG_NAME M_E_MA<12>
J 0
(-2890 2510);
DISPLAY 0.659574 (-2890 2510);
PAINT MONO (-2890 2510);
DISPLAY INVISIBLE (-2890 2510);
FORCEPROP 1 LASTPIN (-2900 2500) BN 12
J 2
(-2848 2508);
DISPLAY 0.617021 (-2848 2508);
PAINT PINK (-2848 2508);
FORCEPROP 2 LAST CDS_LIB mstr_standard
J 0
(-2850 2500);
PAINT MONO (-2850 2500);
DISPLAY INVISIBLE (-2850 2500);
FORCEPROP 1 LAST BODY_TYPE PLUMBING
J 2
(-2850 2450);
DISPLAY 1.595745 (-2850 2450);
PAINT GREEN (-2850 2450);
DISPLAY INVISIBLE (-2850 2450);
FORCEPROP 1 LAST HDL_TAP TRUE
J 2
(-3175 2375);
DISPLAY 1.595745 (-3175 2375);
PAINT GREEN (-3175 2375);
DISPLAY INVISIBLE (-3175 2375);
FORCEPROP 1 LAST PATH I119
J 2
(-2848 2500);
DISPLAY 0.872340 (-2848 2500);
PAINT GREEN (-2848 2500);
DISPLAY INVISIBLE (-2848 2500);
FORCEADD TAP..6
(-5575 950);
FORCEPROP 3 LASTPIN (-5525 950) SIG_NAME M_E_CLK_DP<3>
J 0
(-5515 960);
DISPLAY 0.659574 (-5515 960);
PAINT MONO (-5515 960);
DISPLAY INVISIBLE (-5515 960);
FORCEPROP 1 LASTPIN (-5525 950) BN 3
J 0
(-5577 958);
DISPLAY 0.617021 (-5577 958);
PAINT PINK (-5577 958);
FORCEPROP 2 LAST CDS_LIB mstr_standard
J 0
(-5575 950);
PAINT MONO (-5575 950);
DISPLAY INVISIBLE (-5575 950);
FORCEPROP 1 LAST BODY_TYPE PLUMBING
J 0
(-5575 900);
DISPLAY 1.595745 (-5575 900);
PAINT GREEN (-5575 900);
DISPLAY INVISIBLE (-5575 900);
FORCEPROP 1 LAST HDL_TAP TRUE
J 0
(-5250 825);
DISPLAY 1.595745 (-5250 825);
PAINT GREEN (-5250 825);
DISPLAY INVISIBLE (-5250 825);
FORCEPROP 1 LAST PATH I12
J 0
(-5577 950);
DISPLAY 0.872340 (-5577 950);
PAINT GREEN (-5577 950);
DISPLAY INVISIBLE (-5577 950);
FORCEADD TAP..6
R 2
(-2850 2550);
FORCEPROP 3 LASTPIN (-2900 2550) SIG_NAME M_E_MA<13>
J 0
(-2890 2560);
DISPLAY 0.659574 (-2890 2560);
PAINT MONO (-2890 2560);
DISPLAY INVISIBLE (-2890 2560);
FORCEPROP 1 LASTPIN (-2900 2550) BN 13
J 2
(-2848 2558);
DISPLAY 0.617021 (-2848 2558);
PAINT PINK (-2848 2558);
FORCEPROP 2 LAST CDS_LIB mstr_standard
J 0
(-2850 2550);
PAINT MONO (-2850 2550);
DISPLAY INVISIBLE (-2850 2550);
FORCEPROP 1 LAST BODY_TYPE PLUMBING
J 2
(-2850 2500);
DISPLAY 1.595745 (-2850 2500);
PAINT GREEN (-2850 2500);
DISPLAY INVISIBLE (-2850 2500);
FORCEPROP 1 LAST HDL_TAP TRUE
J 2
(-3175 2425);
DISPLAY 1.595745 (-3175 2425);
PAINT GREEN (-3175 2425);
DISPLAY INVISIBLE (-3175 2425);
FORCEPROP 1 LAST PATH I120
J 2
(-2848 2550);
DISPLAY 0.872340 (-2848 2550);
PAINT GREEN (-2848 2550);
DISPLAY INVISIBLE (-2848 2550);
FORCEADD TAP..6
R 2
(-2850 2600);
FORCEPROP 3 LASTPIN (-2900 2600) SIG_NAME M_E_MA<14>
J 0
(-2890 2610);
DISPLAY 0.659574 (-2890 2610);
PAINT MONO (-2890 2610);
DISPLAY INVISIBLE (-2890 2610);
FORCEPROP 1 LASTPIN (-2900 2600) BN 14
J 2
(-2848 2608);
DISPLAY 0.617021 (-2848 2608);
PAINT PINK (-2848 2608);
FORCEPROP 2 LAST CDS_LIB mstr_standard
J 0
(-2850 2600);
PAINT MONO (-2850 2600);
DISPLAY INVISIBLE (-2850 2600);
FORCEPROP 1 LAST BODY_TYPE PLUMBING
J 2
(-2850 2550);
DISPLAY 1.595745 (-2850 2550);
PAINT GREEN (-2850 2550);
DISPLAY INVISIBLE (-2850 2550);
FORCEPROP 1 LAST HDL_TAP TRUE
J 2
(-3175 2475);
DISPLAY 1.595745 (-3175 2475);
PAINT GREEN (-3175 2475);
DISPLAY INVISIBLE (-3175 2475);
FORCEPROP 1 LAST PATH I121
J 2
(-2848 2600);
DISPLAY 0.872340 (-2848 2600);
PAINT GREEN (-2848 2600);
DISPLAY INVISIBLE (-2848 2600);
FORCEADD TAP..6
R 2
(-2850 2700);
FORCEPROP 3 LASTPIN (-2900 2700) SIG_NAME M_E_MA<16>
J 0
(-2890 2710);
DISPLAY 0.659574 (-2890 2710);
PAINT MONO (-2890 2710);
DISPLAY INVISIBLE (-2890 2710);
FORCEPROP 1 LASTPIN (-2900 2700) BN 16
J 2
(-2848 2708);
DISPLAY 0.617021 (-2848 2708);
PAINT PINK (-2848 2708);
FORCEPROP 2 LAST CDS_LIB mstr_standard
J 0
(-2850 2700);
PAINT MONO (-2850 2700);
DISPLAY INVISIBLE (-2850 2700);
FORCEPROP 1 LAST BODY_TYPE PLUMBING
J 2
(-2850 2650);
DISPLAY 1.595745 (-2850 2650);
PAINT GREEN (-2850 2650);
DISPLAY INVISIBLE (-2850 2650);
FORCEPROP 1 LAST HDL_TAP TRUE
J 2
(-3175 2575);
DISPLAY 1.595745 (-3175 2575);
PAINT GREEN (-3175 2575);
DISPLAY INVISIBLE (-3175 2575);
FORCEPROP 1 LAST PATH I122
J 2
(-2848 2700);
DISPLAY 0.872340 (-2848 2700);
PAINT GREEN (-2848 2700);
DISPLAY INVISIBLE (-2848 2700);
FORCEADD TAP..6
R 2
(-2850 2650);
FORCEPROP 3 LASTPIN (-2900 2650) SIG_NAME M_E_MA<15>
J 0
(-2890 2660);
DISPLAY 0.659574 (-2890 2660);
PAINT MONO (-2890 2660);
DISPLAY INVISIBLE (-2890 2660);
FORCEPROP 1 LASTPIN (-2900 2650) BN 15
J 2
(-2848 2658);
DISPLAY 0.617021 (-2848 2658);
PAINT PINK (-2848 2658);
FORCEPROP 2 LAST CDS_LIB mstr_standard
J 0
(-2850 2650);
PAINT MONO (-2850 2650);
DISPLAY INVISIBLE (-2850 2650);
FORCEPROP 1 LAST BODY_TYPE PLUMBING
J 2
(-2850 2600);
DISPLAY 1.595745 (-2850 2600);
PAINT GREEN (-2850 2600);
DISPLAY INVISIBLE (-2850 2600);
FORCEPROP 1 LAST HDL_TAP TRUE
J 2
(-3175 2525);
DISPLAY 1.595745 (-3175 2525);
PAINT GREEN (-3175 2525);
DISPLAY INVISIBLE (-3175 2525);
FORCEPROP 1 LAST PATH I123
J 2
(-2848 2650);
DISPLAY 0.872340 (-2848 2650);
PAINT GREEN (-2848 2650);
DISPLAY INVISIBLE (-2848 2650);
FORCEADD TAP..6
R 2
(-2850 2750);
FORCEPROP 3 LASTPIN (-2900 2750) SIG_NAME M_E_MA<17>
J 0
(-2890 2760);
DISPLAY 0.659574 (-2890 2760);
PAINT MONO (-2890 2760);
DISPLAY INVISIBLE (-2890 2760);
FORCEPROP 1 LASTPIN (-2900 2750) BN 17
J 2
(-2848 2758);
DISPLAY 0.617021 (-2848 2758);
PAINT PINK (-2848 2758);
FORCEPROP 2 LAST CDS_LIB mstr_standard
J 0
(-2850 2750);
PAINT MONO (-2850 2750);
DISPLAY INVISIBLE (-2850 2750);
FORCEPROP 1 LAST BODY_TYPE PLUMBING
J 2
(-2850 2700);
DISPLAY 1.595745 (-2850 2700);
PAINT GREEN (-2850 2700);
DISPLAY INVISIBLE (-2850 2700);
FORCEPROP 1 LAST HDL_TAP TRUE
J 2
(-3175 2625);
DISPLAY 1.595745 (-3175 2625);
PAINT GREEN (-3175 2625);
DISPLAY INVISIBLE (-3175 2625);
FORCEPROP 1 LAST PATH I124
J 2
(-2848 2750);
DISPLAY 0.872340 (-2848 2750);
PAINT GREEN (-2848 2750);
DISPLAY INVISIBLE (-2848 2750);
FORCEADD TAP..6
R 2
(-2850 2850);
FORCEPROP 3 LASTPIN (-2900 2850) SIG_NAME M_E_DQS_DN<0>
J 0
(-2890 2860);
DISPLAY 0.659574 (-2890 2860);
PAINT MONO (-2890 2860);
DISPLAY INVISIBLE (-2890 2860);
FORCEPROP 1 LASTPIN (-2900 2850) BN 0
J 2
(-2848 2858);
DISPLAY 0.617021 (-2848 2858);
PAINT PINK (-2848 2858);
FORCEPROP 2 LAST CDS_LIB mstr_standard
J 0
(-2850 2850);
PAINT MONO (-2850 2850);
DISPLAY INVISIBLE (-2850 2850);
FORCEPROP 1 LAST BODY_TYPE PLUMBING
J 2
(-2850 2800);
DISPLAY 1.595745 (-2850 2800);
PAINT GREEN (-2850 2800);
DISPLAY INVISIBLE (-2850 2800);
FORCEPROP 1 LAST HDL_TAP TRUE
J 2
(-3175 2725);
DISPLAY 1.595745 (-3175 2725);
PAINT GREEN (-3175 2725);
DISPLAY INVISIBLE (-3175 2725);
FORCEPROP 1 LAST PATH I125
J 2
(-2848 2850);
DISPLAY 0.872340 (-2848 2850);
PAINT GREEN (-2848 2850);
DISPLAY INVISIBLE (-2848 2850);
FORCEADD TAP..6
R 2
(-2850 2950);
FORCEPROP 3 LASTPIN (-2900 2950) SIG_NAME M_E_DQS_DN<2>
J 0
(-2890 2960);
DISPLAY 0.659574 (-2890 2960);
PAINT MONO (-2890 2960);
DISPLAY INVISIBLE (-2890 2960);
FORCEPROP 1 LASTPIN (-2900 2950) BN 2
J 2
(-2848 2958);
DISPLAY 0.617021 (-2848 2958);
PAINT PINK (-2848 2958);
FORCEPROP 2 LAST CDS_LIB mstr_standard
J 0
(-2850 2950);
PAINT MONO (-2850 2950);
DISPLAY INVISIBLE (-2850 2950);
FORCEPROP 1 LAST BODY_TYPE PLUMBING
J 2
(-2850 2900);
DISPLAY 1.595745 (-2850 2900);
PAINT GREEN (-2850 2900);
DISPLAY INVISIBLE (-2850 2900);
FORCEPROP 1 LAST HDL_TAP TRUE
J 2
(-3175 2825);
DISPLAY 1.595745 (-3175 2825);
PAINT GREEN (-3175 2825);
DISPLAY INVISIBLE (-3175 2825);
FORCEPROP 1 LAST PATH I126
J 2
(-2848 2950);
DISPLAY 0.872340 (-2848 2950);
PAINT GREEN (-2848 2950);
DISPLAY INVISIBLE (-2848 2950);
FORCEADD TAP..6
R 2
(-2850 2900);
FORCEPROP 3 LASTPIN (-2900 2900) SIG_NAME M_E_DQS_DN<1>
J 0
(-2890 2910);
DISPLAY 0.659574 (-2890 2910);
PAINT MONO (-2890 2910);
DISPLAY INVISIBLE (-2890 2910);
FORCEPROP 1 LASTPIN (-2900 2900) BN 1
J 2
(-2848 2908);
DISPLAY 0.617021 (-2848 2908);
PAINT PINK (-2848 2908);
FORCEPROP 2 LAST CDS_LIB mstr_standard
J 0
(-2850 2900);
PAINT MONO (-2850 2900);
DISPLAY INVISIBLE (-2850 2900);
FORCEPROP 1 LAST BODY_TYPE PLUMBING
J 2
(-2850 2850);
DISPLAY 1.595745 (-2850 2850);
PAINT GREEN (-2850 2850);
DISPLAY INVISIBLE (-2850 2850);
FORCEPROP 1 LAST HDL_TAP TRUE
J 2
(-3175 2775);
DISPLAY 1.595745 (-3175 2775);
PAINT GREEN (-3175 2775);
DISPLAY INVISIBLE (-3175 2775);
FORCEPROP 1 LAST PATH I127
J 2
(-2848 2900);
DISPLAY 0.872340 (-2848 2900);
PAINT GREEN (-2848 2900);
DISPLAY INVISIBLE (-2848 2900);
FORCEADD TAP..6
R 2
(-2850 3000);
FORCEPROP 3 LASTPIN (-2900 3000) SIG_NAME M_E_DQS_DN<3>
J 0
(-2890 3010);
DISPLAY 0.659574 (-2890 3010);
PAINT MONO (-2890 3010);
DISPLAY INVISIBLE (-2890 3010);
FORCEPROP 1 LASTPIN (-2900 3000) BN 3
J 2
(-2848 3008);
DISPLAY 0.617021 (-2848 3008);
PAINT PINK (-2848 3008);
FORCEPROP 2 LAST CDS_LIB mstr_standard
J 0
(-2850 3000);
PAINT MONO (-2850 3000);
DISPLAY INVISIBLE (-2850 3000);
FORCEPROP 1 LAST BODY_TYPE PLUMBING
J 2
(-2850 2950);
DISPLAY 1.595745 (-2850 2950);
PAINT GREEN (-2850 2950);
DISPLAY INVISIBLE (-2850 2950);
FORCEPROP 1 LAST HDL_TAP TRUE
J 2
(-3175 2875);
DISPLAY 1.595745 (-3175 2875);
PAINT GREEN (-3175 2875);
DISPLAY INVISIBLE (-3175 2875);
FORCEPROP 1 LAST PATH I128
J 2
(-2848 3000);
DISPLAY 0.872340 (-2848 3000);
PAINT GREEN (-2848 3000);
DISPLAY INVISIBLE (-2848 3000);
FORCEADD TAP..6
R 2
(-2850 3050);
FORCEPROP 3 LASTPIN (-2900 3050) SIG_NAME M_E_DQS_DN<4>
J 0
(-2890 3060);
DISPLAY 0.659574 (-2890 3060);
PAINT MONO (-2890 3060);
DISPLAY INVISIBLE (-2890 3060);
FORCEPROP 1 LASTPIN (-2900 3050) BN 4
J 2
(-2848 3058);
DISPLAY 0.617021 (-2848 3058);
PAINT PINK (-2848 3058);
FORCEPROP 2 LAST CDS_LIB mstr_standard
J 0
(-2850 3050);
PAINT MONO (-2850 3050);
DISPLAY INVISIBLE (-2850 3050);
FORCEPROP 1 LAST BODY_TYPE PLUMBING
J 2
(-2850 3000);
DISPLAY 1.595745 (-2850 3000);
PAINT GREEN (-2850 3000);
DISPLAY INVISIBLE (-2850 3000);
FORCEPROP 1 LAST HDL_TAP TRUE
J 2
(-3175 2925);
DISPLAY 1.595745 (-3175 2925);
PAINT GREEN (-3175 2925);
DISPLAY INVISIBLE (-3175 2925);
FORCEPROP 1 LAST PATH I129
J 2
(-2848 3050);
DISPLAY 0.872340 (-2848 3050);
PAINT GREEN (-2848 3050);
DISPLAY INVISIBLE (-2848 3050);
FORCEADD TAP..6
(-5575 1050);
FORCEPROP 3 LASTPIN (-5525 1050) SIG_NAME M_E_ECC<0>
J 0
(-5515 1060);
DISPLAY 0.659574 (-5515 1060);
PAINT MONO (-5515 1060);
DISPLAY INVISIBLE (-5515 1060);
FORCEPROP 1 LASTPIN (-5525 1050) BN 0
J 0
(-5577 1058);
DISPLAY 0.617021 (-5577 1058);
PAINT PINK (-5577 1058);
FORCEPROP 2 LAST CDS_LIB mstr_standard
J 0
(-5575 1050);
PAINT MONO (-5575 1050);
DISPLAY INVISIBLE (-5575 1050);
FORCEPROP 1 LAST BODY_TYPE PLUMBING
J 0
(-5575 1000);
DISPLAY 1.595745 (-5575 1000);
PAINT GREEN (-5575 1000);
DISPLAY INVISIBLE (-5575 1000);
FORCEPROP 1 LAST HDL_TAP TRUE
J 0
(-5250 925);
DISPLAY 1.595745 (-5250 925);
PAINT GREEN (-5250 925);
DISPLAY INVISIBLE (-5250 925);
FORCEPROP 1 LAST PATH I13
J 0
(-5577 1050);
DISPLAY 0.872340 (-5577 1050);
PAINT GREEN (-5577 1050);
DISPLAY INVISIBLE (-5577 1050);
FORCEADD TAP..6
R 2
(-2850 3100);
FORCEPROP 3 LASTPIN (-2900 3100) SIG_NAME M_E_DQS_DN<5>
J 0
(-2890 3110);
DISPLAY 0.659574 (-2890 3110);
PAINT MONO (-2890 3110);
DISPLAY INVISIBLE (-2890 3110);
FORCEPROP 1 LASTPIN (-2900 3100) BN 5
J 2
(-2848 3108);
DISPLAY 0.617021 (-2848 3108);
PAINT PINK (-2848 3108);
FORCEPROP 2 LAST CDS_LIB mstr_standard
J 0
(-2850 3100);
PAINT MONO (-2850 3100);
DISPLAY INVISIBLE (-2850 3100);
FORCEPROP 1 LAST BODY_TYPE PLUMBING
J 2
(-2850 3050);
DISPLAY 1.595745 (-2850 3050);
PAINT GREEN (-2850 3050);
DISPLAY INVISIBLE (-2850 3050);
FORCEPROP 1 LAST HDL_TAP TRUE
J 2
(-3175 2975);
DISPLAY 1.595745 (-3175 2975);
PAINT GREEN (-3175 2975);
DISPLAY INVISIBLE (-3175 2975);
FORCEPROP 1 LAST PATH I130
J 2
(-2848 3100);
DISPLAY 0.872340 (-2848 3100);
PAINT GREEN (-2848 3100);
DISPLAY INVISIBLE (-2848 3100);
FORCEADD TAP..6
R 2
(-2850 3200);
FORCEPROP 3 LASTPIN (-2900 3200) SIG_NAME M_E_DQS_DN<7>
J 0
(-2890 3210);
DISPLAY 0.659574 (-2890 3210);
PAINT MONO (-2890 3210);
DISPLAY INVISIBLE (-2890 3210);
FORCEPROP 1 LASTPIN (-2900 3200) BN 7
J 2
(-2848 3208);
DISPLAY 0.617021 (-2848 3208);
PAINT PINK (-2848 3208);
FORCEPROP 2 LAST CDS_LIB mstr_standard
J 0
(-2850 3200);
PAINT MONO (-2850 3200);
DISPLAY INVISIBLE (-2850 3200);
FORCEPROP 1 LAST BODY_TYPE PLUMBING
J 2
(-2850 3150);
DISPLAY 1.595745 (-2850 3150);
PAINT GREEN (-2850 3150);
DISPLAY INVISIBLE (-2850 3150);
FORCEPROP 1 LAST HDL_TAP TRUE
J 2
(-3175 3075);
DISPLAY 1.595745 (-3175 3075);
PAINT GREEN (-3175 3075);
DISPLAY INVISIBLE (-3175 3075);
FORCEPROP 1 LAST PATH I131
J 2
(-2848 3200);
DISPLAY 0.872340 (-2848 3200);
PAINT GREEN (-2848 3200);
DISPLAY INVISIBLE (-2848 3200);
FORCEADD TAP..6
R 2
(-2850 3150);
FORCEPROP 3 LASTPIN (-2900 3150) SIG_NAME M_E_DQS_DN<6>
J 0
(-2890 3160);
DISPLAY 0.659574 (-2890 3160);
PAINT MONO (-2890 3160);
DISPLAY INVISIBLE (-2890 3160);
FORCEPROP 1 LASTPIN (-2900 3150) BN 6
J 2
(-2848 3158);
DISPLAY 0.617021 (-2848 3158);
PAINT PINK (-2848 3158);
FORCEPROP 2 LAST CDS_LIB mstr_standard
J 0
(-2850 3150);
PAINT MONO (-2850 3150);
DISPLAY INVISIBLE (-2850 3150);
FORCEPROP 1 LAST BODY_TYPE PLUMBING
J 2
(-2850 3100);
DISPLAY 1.595745 (-2850 3100);
PAINT GREEN (-2850 3100);
DISPLAY INVISIBLE (-2850 3100);
FORCEPROP 1 LAST HDL_TAP TRUE
J 2
(-3175 3025);
DISPLAY 1.595745 (-3175 3025);
PAINT GREEN (-3175 3025);
DISPLAY INVISIBLE (-3175 3025);
FORCEPROP 1 LAST PATH I132
J 2
(-2848 3150);
DISPLAY 0.872340 (-2848 3150);
PAINT GREEN (-2848 3150);
DISPLAY INVISIBLE (-2848 3150);
FORCEADD TAP..6
R 2
(-2850 3250);
FORCEPROP 3 LASTPIN (-2900 3250) SIG_NAME M_E_DQS_DN<8>
J 0
(-2890 3260);
DISPLAY 0.659574 (-2890 3260);
PAINT MONO (-2890 3260);
DISPLAY INVISIBLE (-2890 3260);
FORCEPROP 1 LASTPIN (-2900 3250) BN 8
J 2
(-2848 3258);
DISPLAY 0.617021 (-2848 3258);
PAINT PINK (-2848 3258);
FORCEPROP 2 LAST CDS_LIB mstr_standard
J 0
(-2850 3250);
PAINT MONO (-2850 3250);
DISPLAY INVISIBLE (-2850 3250);
FORCEPROP 1 LAST BODY_TYPE PLUMBING
J 2
(-2850 3200);
DISPLAY 1.595745 (-2850 3200);
PAINT GREEN (-2850 3200);
DISPLAY INVISIBLE (-2850 3200);
FORCEPROP 1 LAST HDL_TAP TRUE
J 2
(-3175 3125);
DISPLAY 1.595745 (-3175 3125);
PAINT GREEN (-3175 3125);
DISPLAY INVISIBLE (-3175 3125);
FORCEPROP 1 LAST PATH I133
J 2
(-2848 3250);
DISPLAY 0.872340 (-2848 3250);
PAINT GREEN (-2848 3250);
DISPLAY INVISIBLE (-2848 3250);
FORCEADD TAP..6
R 2
(-2850 3350);
FORCEPROP 3 LASTPIN (-2900 3350) SIG_NAME M_E_DQS_DN<10>
J 0
(-2890 3360);
DISPLAY 0.659574 (-2890 3360);
PAINT MONO (-2890 3360);
DISPLAY INVISIBLE (-2890 3360);
FORCEPROP 1 LASTPIN (-2900 3350) BN 10
J 2
(-2848 3358);
DISPLAY 0.617021 (-2848 3358);
PAINT PINK (-2848 3358);
FORCEPROP 2 LAST CDS_LIB mstr_standard
J 0
(-2850 3350);
PAINT MONO (-2850 3350);
DISPLAY INVISIBLE (-2850 3350);
FORCEPROP 1 LAST BODY_TYPE PLUMBING
J 2
(-2850 3300);
DISPLAY 1.595745 (-2850 3300);
PAINT GREEN (-2850 3300);
DISPLAY INVISIBLE (-2850 3300);
FORCEPROP 1 LAST HDL_TAP TRUE
J 2
(-3175 3225);
DISPLAY 1.595745 (-3175 3225);
PAINT GREEN (-3175 3225);
DISPLAY INVISIBLE (-3175 3225);
FORCEPROP 1 LAST PATH I134
J 2
(-2848 3350);
DISPLAY 0.872340 (-2848 3350);
PAINT GREEN (-2848 3350);
DISPLAY INVISIBLE (-2848 3350);
FORCEADD TAP..6
R 2
(-2850 3300);
FORCEPROP 3 LASTPIN (-2900 3300) SIG_NAME M_E_DQS_DN<9>
J 0
(-2890 3310);
DISPLAY 0.659574 (-2890 3310);
PAINT MONO (-2890 3310);
DISPLAY INVISIBLE (-2890 3310);
FORCEPROP 1 LASTPIN (-2900 3300) BN 9
J 2
(-2848 3308);
DISPLAY 0.617021 (-2848 3308);
PAINT PINK (-2848 3308);
FORCEPROP 2 LAST CDS_LIB mstr_standard
J 0
(-2850 3300);
PAINT MONO (-2850 3300);
DISPLAY INVISIBLE (-2850 3300);
FORCEPROP 1 LAST BODY_TYPE PLUMBING
J 2
(-2850 3250);
DISPLAY 1.595745 (-2850 3250);
PAINT GREEN (-2850 3250);
DISPLAY INVISIBLE (-2850 3250);
FORCEPROP 1 LAST HDL_TAP TRUE
J 2
(-3175 3175);
DISPLAY 1.595745 (-3175 3175);
PAINT GREEN (-3175 3175);
DISPLAY INVISIBLE (-3175 3175);
FORCEPROP 1 LAST PATH I135
J 2
(-2848 3300);
DISPLAY 0.872340 (-2848 3300);
PAINT GREEN (-2848 3300);
DISPLAY INVISIBLE (-2848 3300);
FORCEADD TAP..6
R 2
(-2850 3500);
FORCEPROP 3 LASTPIN (-2900 3500) SIG_NAME M_E_DQS_DN<13>
J 0
(-2890 3510);
DISPLAY 0.659574 (-2890 3510);
PAINT MONO (-2890 3510);
DISPLAY INVISIBLE (-2890 3510);
FORCEPROP 1 LASTPIN (-2900 3500) BN 13
J 2
(-2848 3508);
DISPLAY 0.617021 (-2848 3508);
PAINT PINK (-2848 3508);
FORCEPROP 2 LAST CDS_LIB mstr_standard
J 0
(-2850 3500);
PAINT MONO (-2850 3500);
DISPLAY INVISIBLE (-2850 3500);
FORCEPROP 1 LAST BODY_TYPE PLUMBING
J 2
(-2850 3450);
DISPLAY 1.595745 (-2850 3450);
PAINT GREEN (-2850 3450);
DISPLAY INVISIBLE (-2850 3450);
FORCEPROP 1 LAST HDL_TAP TRUE
J 2
(-3175 3375);
DISPLAY 1.595745 (-3175 3375);
PAINT GREEN (-3175 3375);
DISPLAY INVISIBLE (-3175 3375);
FORCEPROP 1 LAST PATH I136
J 2
(-2848 3500);
DISPLAY 0.872340 (-2848 3500);
PAINT GREEN (-2848 3500);
DISPLAY INVISIBLE (-2848 3500);
FORCEADD TAP..6
R 2
(-2850 3400);
FORCEPROP 3 LASTPIN (-2900 3400) SIG_NAME M_E_DQS_DN<11>
J 0
(-2890 3410);
DISPLAY 0.659574 (-2890 3410);
PAINT MONO (-2890 3410);
DISPLAY INVISIBLE (-2890 3410);
FORCEPROP 1 LASTPIN (-2900 3400) BN 11
J 2
(-2848 3408);
DISPLAY 0.617021 (-2848 3408);
PAINT PINK (-2848 3408);
FORCEPROP 2 LAST CDS_LIB mstr_standard
J 0
(-2850 3400);
PAINT MONO (-2850 3400);
DISPLAY INVISIBLE (-2850 3400);
FORCEPROP 1 LAST BODY_TYPE PLUMBING
J 2
(-2850 3350);
DISPLAY 1.595745 (-2850 3350);
PAINT GREEN (-2850 3350);
DISPLAY INVISIBLE (-2850 3350);
FORCEPROP 1 LAST HDL_TAP TRUE
J 2
(-3175 3275);
DISPLAY 1.595745 (-3175 3275);
PAINT GREEN (-3175 3275);
DISPLAY INVISIBLE (-3175 3275);
FORCEPROP 1 LAST PATH I137
J 2
(-2848 3400);
DISPLAY 0.872340 (-2848 3400);
PAINT GREEN (-2848 3400);
DISPLAY INVISIBLE (-2848 3400);
FORCEADD TAP..6
R 2
(-2850 3450);
FORCEPROP 3 LASTPIN (-2900 3450) SIG_NAME M_E_DQS_DN<12>
J 0
(-2890 3460);
DISPLAY 0.659574 (-2890 3460);
PAINT MONO (-2890 3460);
DISPLAY INVISIBLE (-2890 3460);
FORCEPROP 1 LASTPIN (-2900 3450) BN 12
J 2
(-2848 3458);
DISPLAY 0.617021 (-2848 3458);
PAINT PINK (-2848 3458);
FORCEPROP 2 LAST CDS_LIB mstr_standard
J 0
(-2850 3450);
PAINT MONO (-2850 3450);
DISPLAY INVISIBLE (-2850 3450);
FORCEPROP 1 LAST BODY_TYPE PLUMBING
J 2
(-2850 3400);
DISPLAY 1.595745 (-2850 3400);
PAINT GREEN (-2850 3400);
DISPLAY INVISIBLE (-2850 3400);
FORCEPROP 1 LAST HDL_TAP TRUE
J 2
(-3175 3325);
DISPLAY 1.595745 (-3175 3325);
PAINT GREEN (-3175 3325);
DISPLAY INVISIBLE (-3175 3325);
FORCEPROP 1 LAST PATH I138
J 2
(-2848 3450);
DISPLAY 0.872340 (-2848 3450);
PAINT GREEN (-2848 3450);
DISPLAY INVISIBLE (-2848 3450);
FORCEADD TAP..6
R 2
(-2850 3600);
FORCEPROP 3 LASTPIN (-2900 3600) SIG_NAME M_E_DQS_DN<15>
J 0
(-2890 3610);
DISPLAY 0.659574 (-2890 3610);
PAINT MONO (-2890 3610);
DISPLAY INVISIBLE (-2890 3610);
FORCEPROP 1 LASTPIN (-2900 3600) BN 15
J 2
(-2848 3608);
DISPLAY 0.617021 (-2848 3608);
PAINT PINK (-2848 3608);
FORCEPROP 2 LAST CDS_LIB mstr_standard
J 0
(-2850 3600);
PAINT MONO (-2850 3600);
DISPLAY INVISIBLE (-2850 3600);
FORCEPROP 1 LAST BODY_TYPE PLUMBING
J 2
(-2850 3550);
DISPLAY 1.595745 (-2850 3550);
PAINT GREEN (-2850 3550);
DISPLAY INVISIBLE (-2850 3550);
FORCEPROP 1 LAST HDL_TAP TRUE
J 2
(-3175 3475);
DISPLAY 1.595745 (-3175 3475);
PAINT GREEN (-3175 3475);
DISPLAY INVISIBLE (-3175 3475);
FORCEPROP 1 LAST PATH I139
J 2
(-2848 3600);
DISPLAY 0.872340 (-2848 3600);
PAINT GREEN (-2848 3600);
DISPLAY INVISIBLE (-2848 3600);
FORCEADD TAP..6
(-5575 1100);
FORCEPROP 3 LASTPIN (-5525 1100) SIG_NAME M_E_ECC<1>
J 0
(-5515 1110);
DISPLAY 0.659574 (-5515 1110);
PAINT MONO (-5515 1110);
DISPLAY INVISIBLE (-5515 1110);
FORCEPROP 1 LASTPIN (-5525 1100) BN 1
J 0
(-5577 1108);
DISPLAY 0.617021 (-5577 1108);
PAINT PINK (-5577 1108);
FORCEPROP 2 LAST CDS_LIB mstr_standard
J 0
(-5575 1100);
PAINT MONO (-5575 1100);
DISPLAY INVISIBLE (-5575 1100);
FORCEPROP 1 LAST BODY_TYPE PLUMBING
J 0
(-5575 1050);
DISPLAY 1.595745 (-5575 1050);
PAINT GREEN (-5575 1050);
DISPLAY INVISIBLE (-5575 1050);
FORCEPROP 1 LAST HDL_TAP TRUE
J 0
(-5250 975);
DISPLAY 1.595745 (-5250 975);
PAINT GREEN (-5250 975);
DISPLAY INVISIBLE (-5250 975);
FORCEPROP 1 LAST PATH I14
J 0
(-5577 1100);
DISPLAY 0.872340 (-5577 1100);
PAINT GREEN (-5577 1100);
DISPLAY INVISIBLE (-5577 1100);
FORCEADD TAP..6
R 2
(-2850 3550);
FORCEPROP 3 LASTPIN (-2900 3550) SIG_NAME M_E_DQS_DN<14>
J 0
(-2890 3560);
DISPLAY 0.659574 (-2890 3560);
PAINT MONO (-2890 3560);
DISPLAY INVISIBLE (-2890 3560);
FORCEPROP 1 LASTPIN (-2900 3550) BN 14
J 2
(-2848 3558);
DISPLAY 0.617021 (-2848 3558);
PAINT PINK (-2848 3558);
FORCEPROP 2 LAST CDS_LIB mstr_standard
J 0
(-2850 3550);
PAINT MONO (-2850 3550);
DISPLAY INVISIBLE (-2850 3550);
FORCEPROP 1 LAST BODY_TYPE PLUMBING
J 2
(-2850 3500);
DISPLAY 1.595745 (-2850 3500);
PAINT GREEN (-2850 3500);
DISPLAY INVISIBLE (-2850 3500);
FORCEPROP 1 LAST HDL_TAP TRUE
J 2
(-3175 3425);
DISPLAY 1.595745 (-3175 3425);
PAINT GREEN (-3175 3425);
DISPLAY INVISIBLE (-3175 3425);
FORCEPROP 1 LAST PATH I140
J 2
(-2848 3550);
DISPLAY 0.872340 (-2848 3550);
PAINT GREEN (-2848 3550);
DISPLAY INVISIBLE (-2848 3550);
FORCEADD TAP..6
R 2
(-2850 3700);
FORCEPROP 3 LASTPIN (-2900 3700) SIG_NAME M_E_DQS_DN<17>
J 0
(-2890 3710);
DISPLAY 0.659574 (-2890 3710);
PAINT MONO (-2890 3710);
DISPLAY INVISIBLE (-2890 3710);
FORCEPROP 1 LASTPIN (-2900 3700) BN 17
J 2
(-2848 3708);
DISPLAY 0.617021 (-2848 3708);
PAINT PINK (-2848 3708);
FORCEPROP 2 LAST CDS_LIB mstr_standard
J 0
(-2850 3700);
PAINT MONO (-2850 3700);
DISPLAY INVISIBLE (-2850 3700);
FORCEPROP 1 LAST BODY_TYPE PLUMBING
J 2
(-2850 3650);
DISPLAY 1.595745 (-2850 3650);
PAINT GREEN (-2850 3650);
DISPLAY INVISIBLE (-2850 3650);
FORCEPROP 1 LAST HDL_TAP TRUE
J 2
(-3175 3575);
DISPLAY 1.595745 (-3175 3575);
PAINT GREEN (-3175 3575);
DISPLAY INVISIBLE (-3175 3575);
FORCEPROP 1 LAST PATH I141
J 2
(-2848 3700);
DISPLAY 0.872340 (-2848 3700);
PAINT GREEN (-2848 3700);
DISPLAY INVISIBLE (-2848 3700);
FORCEADD TAP..6
R 2
(-2850 3650);
FORCEPROP 3 LASTPIN (-2900 3650) SIG_NAME M_E_DQS_DN<16>
J 0
(-2890 3660);
DISPLAY 0.659574 (-2890 3660);
PAINT MONO (-2890 3660);
DISPLAY INVISIBLE (-2890 3660);
FORCEPROP 1 LASTPIN (-2900 3650) BN 16
J 2
(-2848 3658);
DISPLAY 0.617021 (-2848 3658);
PAINT PINK (-2848 3658);
FORCEPROP 2 LAST CDS_LIB mstr_standard
J 0
(-2850 3650);
PAINT MONO (-2850 3650);
DISPLAY INVISIBLE (-2850 3650);
FORCEPROP 1 LAST BODY_TYPE PLUMBING
J 2
(-2850 3600);
DISPLAY 1.595745 (-2850 3600);
PAINT GREEN (-2850 3600);
DISPLAY INVISIBLE (-2850 3600);
FORCEPROP 1 LAST HDL_TAP TRUE
J 2
(-3175 3525);
DISPLAY 1.595745 (-3175 3525);
PAINT GREEN (-3175 3525);
DISPLAY INVISIBLE (-3175 3525);
FORCEPROP 1 LAST PATH I142
J 2
(-2848 3650);
DISPLAY 0.872340 (-2848 3650);
PAINT GREEN (-2848 3650);
DISPLAY INVISIBLE (-2848 3650);
FORCEADD TAP..6
R 2
(-2850 3850);
FORCEPROP 3 LASTPIN (-2900 3850) SIG_NAME M_E_DQS_DP<1>
J 0
(-2890 3860);
DISPLAY 0.659574 (-2890 3860);
PAINT MONO (-2890 3860);
DISPLAY INVISIBLE (-2890 3860);
FORCEPROP 1 LASTPIN (-2900 3850) BN 1
J 2
(-2848 3858);
DISPLAY 0.617021 (-2848 3858);
PAINT PINK (-2848 3858);
FORCEPROP 2 LAST CDS_LIB mstr_standard
J 0
(-2850 3850);
PAINT MONO (-2850 3850);
DISPLAY INVISIBLE (-2850 3850);
FORCEPROP 1 LAST BODY_TYPE PLUMBING
J 2
(-2850 3800);
DISPLAY 1.595745 (-2850 3800);
PAINT GREEN (-2850 3800);
DISPLAY INVISIBLE (-2850 3800);
FORCEPROP 1 LAST HDL_TAP TRUE
J 2
(-3175 3725);
DISPLAY 1.595745 (-3175 3725);
PAINT GREEN (-3175 3725);
DISPLAY INVISIBLE (-3175 3725);
FORCEPROP 1 LAST PATH I143
J 2
(-2848 3850);
DISPLAY 0.872340 (-2848 3850);
PAINT GREEN (-2848 3850);
DISPLAY INVISIBLE (-2848 3850);
FORCEADD TAP..6
R 2
(-2850 3800);
FORCEPROP 3 LASTPIN (-2900 3800) SIG_NAME M_E_DQS_DP<0>
J 0
(-2890 3810);
DISPLAY 0.659574 (-2890 3810);
PAINT MONO (-2890 3810);
DISPLAY INVISIBLE (-2890 3810);
FORCEPROP 1 LASTPIN (-2900 3800) BN 0
J 2
(-2848 3808);
DISPLAY 0.617021 (-2848 3808);
PAINT PINK (-2848 3808);
FORCEPROP 2 LAST CDS_LIB mstr_standard
J 0
(-2850 3800);
PAINT MONO (-2850 3800);
DISPLAY INVISIBLE (-2850 3800);
FORCEPROP 1 LAST BODY_TYPE PLUMBING
J 2
(-2850 3750);
DISPLAY 1.595745 (-2850 3750);
PAINT GREEN (-2850 3750);
DISPLAY INVISIBLE (-2850 3750);
FORCEPROP 1 LAST HDL_TAP TRUE
J 2
(-3175 3675);
DISPLAY 1.595745 (-3175 3675);
PAINT GREEN (-3175 3675);
DISPLAY INVISIBLE (-3175 3675);
FORCEPROP 1 LAST PATH I144
J 2
(-2848 3800);
DISPLAY 0.872340 (-2848 3800);
PAINT GREEN (-2848 3800);
DISPLAY INVISIBLE (-2848 3800);
FORCEADD TAP..6
R 2
(-2850 4000);
FORCEPROP 3 LASTPIN (-2900 4000) SIG_NAME M_E_DQS_DP<4>
J 0
(-2890 4010);
DISPLAY 0.659574 (-2890 4010);
PAINT MONO (-2890 4010);
DISPLAY INVISIBLE (-2890 4010);
FORCEPROP 1 LASTPIN (-2900 4000) BN 4
J 2
(-2848 4008);
DISPLAY 0.617021 (-2848 4008);
PAINT PINK (-2848 4008);
FORCEPROP 2 LAST CDS_LIB mstr_standard
J 0
(-2850 4000);
PAINT MONO (-2850 4000);
DISPLAY INVISIBLE (-2850 4000);
FORCEPROP 1 LAST BODY_TYPE PLUMBING
J 2
(-2850 3950);
DISPLAY 1.595745 (-2850 3950);
PAINT GREEN (-2850 3950);
DISPLAY INVISIBLE (-2850 3950);
FORCEPROP 1 LAST HDL_TAP TRUE
J 2
(-3175 3875);
DISPLAY 1.595745 (-3175 3875);
PAINT GREEN (-3175 3875);
DISPLAY INVISIBLE (-3175 3875);
FORCEPROP 1 LAST PATH I145
J 2
(-2848 4000);
DISPLAY 0.872340 (-2848 4000);
PAINT GREEN (-2848 4000);
DISPLAY INVISIBLE (-2848 4000);
FORCEADD TAP..6
R 2
(-2850 3950);
FORCEPROP 3 LASTPIN (-2900 3950) SIG_NAME M_E_DQS_DP<3>
J 0
(-2890 3960);
DISPLAY 0.659574 (-2890 3960);
PAINT MONO (-2890 3960);
DISPLAY INVISIBLE (-2890 3960);
FORCEPROP 1 LASTPIN (-2900 3950) BN 3
J 2
(-2848 3958);
DISPLAY 0.617021 (-2848 3958);
PAINT PINK (-2848 3958);
FORCEPROP 2 LAST CDS_LIB mstr_standard
J 0
(-2850 3950);
PAINT MONO (-2850 3950);
DISPLAY INVISIBLE (-2850 3950);
FORCEPROP 1 LAST BODY_TYPE PLUMBING
J 2
(-2850 3900);
DISPLAY 1.595745 (-2850 3900);
PAINT GREEN (-2850 3900);
DISPLAY INVISIBLE (-2850 3900);
FORCEPROP 1 LAST HDL_TAP TRUE
J 2
(-3175 3825);
DISPLAY 1.595745 (-3175 3825);
PAINT GREEN (-3175 3825);
DISPLAY INVISIBLE (-3175 3825);
FORCEPROP 1 LAST PATH I146
J 2
(-2848 3950);
DISPLAY 0.872340 (-2848 3950);
PAINT GREEN (-2848 3950);
DISPLAY INVISIBLE (-2848 3950);
FORCEADD TAP..6
R 2
(-2850 3900);
FORCEPROP 3 LASTPIN (-2900 3900) SIG_NAME M_E_DQS_DP<2>
J 0
(-2890 3910);
DISPLAY 0.659574 (-2890 3910);
PAINT MONO (-2890 3910);
DISPLAY INVISIBLE (-2890 3910);
FORCEPROP 1 LASTPIN (-2900 3900) BN 2
J 2
(-2848 3908);
DISPLAY 0.617021 (-2848 3908);
PAINT PINK (-2848 3908);
FORCEPROP 2 LAST CDS_LIB mstr_standard
J 0
(-2850 3900);
PAINT MONO (-2850 3900);
DISPLAY INVISIBLE (-2850 3900);
FORCEPROP 1 LAST BODY_TYPE PLUMBING
J 2
(-2850 3850);
DISPLAY 1.595745 (-2850 3850);
PAINT GREEN (-2850 3850);
DISPLAY INVISIBLE (-2850 3850);
FORCEPROP 1 LAST HDL_TAP TRUE
J 2
(-3175 3775);
DISPLAY 1.595745 (-3175 3775);
PAINT GREEN (-3175 3775);
DISPLAY INVISIBLE (-3175 3775);
FORCEPROP 1 LAST PATH I147
J 2
(-2848 3900);
DISPLAY 0.872340 (-2848 3900);
PAINT GREEN (-2848 3900);
DISPLAY INVISIBLE (-2848 3900);
FORCEADD OFFPAGE..4
(-2000 550);
FORCEPROP 2 LAST $XR0 51 
J 0
(-1814 550);
DISPLAY 0.638298 (-1814 550);
PAINT MONO (-1814 550);
FORCEPROP 2 LAST $XR1 52 
J 0
(-1724 550);
DISPLAY 0.638298 (-1724 550);
PAINT MONO (-1724 550);
FORCEPROP 2 LAST CDS_LIB mstr_standard
J 0
(-2000 550);
PAINT MONO (-2000 550);
DISPLAY INVISIBLE (-2000 550);
FORCEPROP 1 LAST OFFPAGE TRUE
J 0
(-1675 425);
DISPLAY 1.170213 (-1675 425);
PAINT GREEN (-1675 425);
DISPLAY INVISIBLE (-1675 425);
FORCEPROP 1 LAST COMMENT_BODY TRUE
J 0
(-2025 450);
DISPLAY 1.170213 (-2025 450);
PAINT GREEN (-2025 450);
DISPLAY INVISIBLE (-2025 450);
FORCEPROP 2 LAST PATH I148
J 0
(-1825 625);
DISPLAY 1.021277 (-1825 625);
PAINT ORANGE (-1825 625);
DISPLAY INVISIBLE (-1825 625);
FORCEADD OFFPAGE..2
(-2000 500);
FORCEPROP 2 LAST $XR0 51 
J 0
(-1811 500);
DISPLAY 0.638298 (-1811 500);
PAINT MONO (-1811 500);
FORCEPROP 2 LAST $XR1 52 
J 0
(-1721 500);
DISPLAY 0.638298 (-1721 500);
PAINT MONO (-1721 500);
FORCEPROP 2 LAST CDS_LIB mstr_standard
J 0
(-2000 500);
PAINT MONO (-2000 500);
DISPLAY INVISIBLE (-2000 500);
FORCEPROP 1 LAST OFFPAGE TRUE
J 0
(-1675 375);
DISPLAY 1.170213 (-1675 375);
PAINT GREEN (-1675 375);
DISPLAY INVISIBLE (-1675 375);
FORCEPROP 1 LAST COMMENT_BODY TRUE
J 0
(-2045 405);
DISPLAY 1.170213 (-2045 405);
PAINT GREEN (-2045 405);
DISPLAY INVISIBLE (-2045 405);
FORCEPROP 2 LAST PATH I149
J 0
(-1825 575);
DISPLAY 1.021277 (-1825 575);
PAINT ORANGE (-1825 575);
DISPLAY INVISIBLE (-1825 575);
FORCEADD TAP..6
(-5575 1150);
FORCEPROP 3 LASTPIN (-5525 1150) SIG_NAME M_E_ECC<2>
J 0
(-5515 1160);
DISPLAY 0.659574 (-5515 1160);
PAINT MONO (-5515 1160);
DISPLAY INVISIBLE (-5515 1160);
FORCEPROP 1 LASTPIN (-5525 1150) BN 2
J 0
(-5577 1158);
DISPLAY 0.617021 (-5577 1158);
PAINT PINK (-5577 1158);
FORCEPROP 2 LAST CDS_LIB mstr_standard
J 0
(-5575 1150);
PAINT MONO (-5575 1150);
DISPLAY INVISIBLE (-5575 1150);
FORCEPROP 1 LAST BODY_TYPE PLUMBING
J 0
(-5575 1100);
DISPLAY 1.595745 (-5575 1100);
PAINT GREEN (-5575 1100);
DISPLAY INVISIBLE (-5575 1100);
FORCEPROP 1 LAST HDL_TAP TRUE
J 0
(-5250 1025);
DISPLAY 1.595745 (-5250 1025);
PAINT GREEN (-5250 1025);
DISPLAY INVISIBLE (-5250 1025);
FORCEPROP 1 LAST PATH I15
J 0
(-5577 1150);
DISPLAY 0.872340 (-5577 1150);
PAINT GREEN (-5577 1150);
DISPLAY INVISIBLE (-5577 1150);
FORCEADD OFFPAGE..2
(-2000 600);
FORCEPROP 2 LAST $XR0 51 
J 0
(-1811 600);
DISPLAY 0.638298 (-1811 600);
PAINT MONO (-1811 600);
FORCEPROP 2 LAST $XR1 52 
J 0
(-1721 600);
DISPLAY 0.638298 (-1721 600);
PAINT MONO (-1721 600);
FORCEPROP 2 LAST CDS_LIB mstr_standard
J 0
(-2000 600);
PAINT MONO (-2000 600);
DISPLAY INVISIBLE (-2000 600);
FORCEPROP 1 LAST OFFPAGE TRUE
J 0
(-1675 475);
DISPLAY 1.170213 (-1675 475);
PAINT GREEN (-1675 475);
DISPLAY INVISIBLE (-1675 475);
FORCEPROP 1 LAST COMMENT_BODY TRUE
J 0
(-2045 505);
DISPLAY 1.170213 (-2045 505);
PAINT GREEN (-2045 505);
DISPLAY INVISIBLE (-2045 505);
FORCEPROP 2 LAST PATH I150
J 0
(-1825 675);
DISPLAY 1.021277 (-1825 675);
PAINT ORANGE (-1825 675);
DISPLAY INVISIBLE (-1825 675);
FORCEADD OFFPAGE..2
(-2000 800);
FORCEPROP 2 LAST $XR0 51 
J 0
(-1811 800);
DISPLAY 0.638298 (-1811 800);
PAINT MONO (-1811 800);
FORCEPROP 2 LAST $XR1 52 
J 0
(-1721 800);
DISPLAY 0.638298 (-1721 800);
PAINT MONO (-1721 800);
FORCEPROP 2 LAST CDS_LIB mstr_standard
J 0
(-2000 800);
PAINT MONO (-2000 800);
DISPLAY INVISIBLE (-2000 800);
FORCEPROP 1 LAST OFFPAGE TRUE
J 0
(-1675 675);
DISPLAY 1.170213 (-1675 675);
PAINT GREEN (-1675 675);
DISPLAY INVISIBLE (-1675 675);
FORCEPROP 1 LAST COMMENT_BODY TRUE
J 0
(-2045 705);
DISPLAY 1.170213 (-2045 705);
PAINT GREEN (-2045 705);
DISPLAY INVISIBLE (-2045 705);
FORCEPROP 2 LAST PATH I151
J 0
(-1825 875);
DISPLAY 1.021277 (-1825 875);
PAINT ORANGE (-1825 875);
DISPLAY INVISIBLE (-1825 875);
FORCEADD OFFPAGE..2
(-2000 900);
FORCEPROP 2 LAST $XR0 51 
J 0
(-1811 900);
DISPLAY 0.638298 (-1811 900);
PAINT MONO (-1811 900);
FORCEPROP 2 LAST $XR1 52 
J 0
(-1721 900);
DISPLAY 0.638298 (-1721 900);
PAINT MONO (-1721 900);
FORCEPROP 2 LAST CDS_LIB mstr_standard
J 0
(-2000 900);
PAINT MONO (-2000 900);
DISPLAY INVISIBLE (-2000 900);
FORCEPROP 1 LAST OFFPAGE TRUE
J 0
(-1675 775);
DISPLAY 1.170213 (-1675 775);
PAINT GREEN (-1675 775);
DISPLAY INVISIBLE (-1675 775);
FORCEPROP 1 LAST COMMENT_BODY TRUE
J 0
(-2045 805);
DISPLAY 1.170213 (-2045 805);
PAINT GREEN (-2045 805);
DISPLAY INVISIBLE (-2045 805);
FORCEPROP 2 LAST PATH I152
J 0
(-1825 975);
DISPLAY 1.021277 (-1825 975);
PAINT ORANGE (-1825 975);
DISPLAY INVISIBLE (-1825 975);
FORCEADD OFFPAGE..2
(-2000 1350);
FORCEPROP 2 LAST $XR0 51 
J 0
(-1811 1350);
DISPLAY 0.638298 (-1811 1350);
PAINT MONO (-1811 1350);
FORCEPROP 2 LAST $XR1 52 
J 0
(-1721 1350);
DISPLAY 0.638298 (-1721 1350);
PAINT MONO (-1721 1350);
FORCEPROP 2 LAST CDS_LIB mstr_standard
J 0
(-2000 1350);
PAINT MONO (-2000 1350);
DISPLAY INVISIBLE (-2000 1350);
FORCEPROP 1 LAST OFFPAGE TRUE
J 0
(-1675 1225);
DISPLAY 1.170213 (-1675 1225);
PAINT GREEN (-1675 1225);
DISPLAY INVISIBLE (-1675 1225);
FORCEPROP 1 LAST COMMENT_BODY TRUE
J 0
(-2045 1255);
DISPLAY 1.170213 (-2045 1255);
PAINT GREEN (-2045 1255);
DISPLAY INVISIBLE (-2045 1255);
FORCEPROP 2 LAST PATH I153
J 0
(-1825 1425);
DISPLAY 1.021277 (-1825 1425);
PAINT ORANGE (-1825 1425);
DISPLAY INVISIBLE (-1825 1425);
FORCEADD OFFPAGE..2
(-2000 1600);
FORCEPROP 2 LAST $XR0 51 
J 0
(-1811 1600);
DISPLAY 0.638298 (-1811 1600);
PAINT MONO (-1811 1600);
FORCEPROP 2 LAST $XR1 52 
J 0
(-1721 1600);
DISPLAY 0.638298 (-1721 1600);
PAINT MONO (-1721 1600);
FORCEPROP 2 LAST CDS_LIB mstr_standard
J 0
(-2000 1600);
PAINT MONO (-2000 1600);
DISPLAY INVISIBLE (-2000 1600);
FORCEPROP 1 LAST OFFPAGE TRUE
J 0
(-1675 1475);
DISPLAY 1.170213 (-1675 1475);
PAINT GREEN (-1675 1475);
DISPLAY INVISIBLE (-1675 1475);
FORCEPROP 1 LAST COMMENT_BODY TRUE
J 0
(-2045 1505);
DISPLAY 1.170213 (-2045 1505);
PAINT GREEN (-2045 1505);
DISPLAY INVISIBLE (-2045 1505);
FORCEPROP 2 LAST PATH I154
J 0
(-1825 1675);
DISPLAY 1.021277 (-1825 1675);
PAINT ORANGE (-1825 1675);
DISPLAY INVISIBLE (-1825 1675);
FORCEADD OFFPAGE..2
(-2000 1850);
FORCEPROP 2 LAST $XR0 51 
J 0
(-1811 1850);
DISPLAY 0.638298 (-1811 1850);
PAINT MONO (-1811 1850);
FORCEPROP 2 LAST $XR1 52 
J 0
(-1721 1850);
DISPLAY 0.638298 (-1721 1850);
PAINT MONO (-1721 1850);
FORCEPROP 2 LAST CDS_LIB mstr_standard
J 0
(-2000 1850);
PAINT MONO (-2000 1850);
DISPLAY INVISIBLE (-2000 1850);
FORCEPROP 1 LAST OFFPAGE TRUE
J 0
(-1675 1725);
DISPLAY 1.170213 (-1675 1725);
PAINT GREEN (-1675 1725);
DISPLAY INVISIBLE (-1675 1725);
FORCEPROP 1 LAST COMMENT_BODY TRUE
J 0
(-2045 1755);
DISPLAY 1.170213 (-2045 1755);
PAINT GREEN (-2045 1755);
DISPLAY INVISIBLE (-2045 1755);
FORCEPROP 2 LAST PATH I155
J 0
(-1825 1925);
DISPLAY 1.021277 (-1825 1925);
PAINT ORANGE (-1825 1925);
DISPLAY INVISIBLE (-1825 1925);
FORCEADD OFFPAGE..2
(-2000 2800);
FORCEPROP 2 LAST $XR0 51 
J 0
(-1811 2800);
DISPLAY 0.638298 (-1811 2800);
PAINT MONO (-1811 2800);
FORCEPROP 2 LAST $XR1 52 
J 0
(-1721 2800);
DISPLAY 0.638298 (-1721 2800);
PAINT MONO (-1721 2800);
FORCEPROP 2 LAST CDS_LIB mstr_standard
J 0
(-2000 2800);
PAINT MONO (-2000 2800);
DISPLAY INVISIBLE (-2000 2800);
FORCEPROP 1 LAST OFFPAGE TRUE
J 0
(-1675 2675);
DISPLAY 1.170213 (-1675 2675);
PAINT GREEN (-1675 2675);
DISPLAY INVISIBLE (-1675 2675);
FORCEPROP 1 LAST COMMENT_BODY TRUE
J 0
(-2045 2705);
DISPLAY 1.170213 (-2045 2705);
PAINT GREEN (-2045 2705);
DISPLAY INVISIBLE (-2045 2705);
FORCEPROP 2 LAST PATH I156
J 0
(-1825 2875);
DISPLAY 1.021277 (-1825 2875);
PAINT ORANGE (-1825 2875);
DISPLAY INVISIBLE (-1825 2875);
FORCEADD OFFPAGE..3
(-2000 3750);
FORCEPROP 2 LAST $XR0 51 
J 0
(-1786 3750);
DISPLAY 0.638298 (-1786 3750);
PAINT MONO (-1786 3750);
FORCEPROP 2 LAST $XR1 52 
J 0
(-1696 3750);
DISPLAY 0.638298 (-1696 3750);
PAINT MONO (-1696 3750);
FORCEPROP 2 LAST CDS_LIB mstr_standard
J 0
(-2000 3750);
PAINT MONO (-2000 3750);
DISPLAY INVISIBLE (-2000 3750);
FORCEPROP 1 LAST OFFPAGE TRUE
J 0
(-1675 3625);
DISPLAY 1.170213 (-1675 3625);
PAINT GREEN (-1675 3625);
DISPLAY INVISIBLE (-1675 3625);
FORCEPROP 1 LAST COMMENT_BODY TRUE
J 0
(-2050 3650);
DISPLAY 1.170213 (-2050 3650);
PAINT GREEN (-2050 3650);
DISPLAY INVISIBLE (-2050 3650);
FORCEPROP 2 LAST PATH I157
J 0
(-1800 3825);
DISPLAY 1.021277 (-1800 3825);
PAINT ORANGE (-1800 3825);
DISPLAY INVISIBLE (-1800 3825);
FORCEADD TAP..6
R 2
(-2850 4100);
FORCEPROP 3 LASTPIN (-2900 4100) SIG_NAME M_E_DQS_DP<6>
J 0
(-2890 4110);
DISPLAY 0.659574 (-2890 4110);
PAINT MONO (-2890 4110);
DISPLAY INVISIBLE (-2890 4110);
FORCEPROP 1 LASTPIN (-2900 4100) BN 6
J 2
(-2848 4108);
DISPLAY 0.617021 (-2848 4108);
PAINT PINK (-2848 4108);
FORCEPROP 2 LAST CDS_LIB mstr_standard
J 0
(-2850 4100);
PAINT MONO (-2850 4100);
DISPLAY INVISIBLE (-2850 4100);
FORCEPROP 1 LAST BODY_TYPE PLUMBING
J 2
(-2850 4050);
DISPLAY 1.595745 (-2850 4050);
PAINT GREEN (-2850 4050);
DISPLAY INVISIBLE (-2850 4050);
FORCEPROP 1 LAST HDL_TAP TRUE
J 2
(-3175 3975);
DISPLAY 1.595745 (-3175 3975);
PAINT GREEN (-3175 3975);
DISPLAY INVISIBLE (-3175 3975);
FORCEPROP 1 LAST PATH I158
J 2
(-2848 4100);
DISPLAY 0.872340 (-2848 4100);
PAINT GREEN (-2848 4100);
DISPLAY INVISIBLE (-2848 4100);
FORCEADD TAP..6
R 2
(-2850 4050);
FORCEPROP 3 LASTPIN (-2900 4050) SIG_NAME M_E_DQS_DP<5>
J 0
(-2890 4060);
DISPLAY 0.659574 (-2890 4060);
PAINT MONO (-2890 4060);
DISPLAY INVISIBLE (-2890 4060);
FORCEPROP 1 LASTPIN (-2900 4050) BN 5
J 2
(-2848 4058);
DISPLAY 0.617021 (-2848 4058);
PAINT PINK (-2848 4058);
FORCEPROP 2 LAST CDS_LIB mstr_standard
J 0
(-2850 4050);
PAINT MONO (-2850 4050);
DISPLAY INVISIBLE (-2850 4050);
FORCEPROP 1 LAST BODY_TYPE PLUMBING
J 2
(-2850 4000);
DISPLAY 1.595745 (-2850 4000);
PAINT GREEN (-2850 4000);
DISPLAY INVISIBLE (-2850 4000);
FORCEPROP 1 LAST HDL_TAP TRUE
J 2
(-3175 3925);
DISPLAY 1.595745 (-3175 3925);
PAINT GREEN (-3175 3925);
DISPLAY INVISIBLE (-3175 3925);
FORCEPROP 1 LAST PATH I159
J 2
(-2848 4050);
DISPLAY 0.872340 (-2848 4050);
PAINT GREEN (-2848 4050);
DISPLAY INVISIBLE (-2848 4050);
FORCEADD TAP..6
(-5575 1200);
FORCEPROP 3 LASTPIN (-5525 1200) SIG_NAME M_E_ECC<3>
J 0
(-5515 1210);
DISPLAY 0.659574 (-5515 1210);
PAINT MONO (-5515 1210);
DISPLAY INVISIBLE (-5515 1210);
FORCEPROP 1 LASTPIN (-5525 1200) BN 3
J 0
(-5577 1208);
DISPLAY 0.617021 (-5577 1208);
PAINT PINK (-5577 1208);
FORCEPROP 2 LAST CDS_LIB mstr_standard
J 0
(-5575 1200);
PAINT MONO (-5575 1200);
DISPLAY INVISIBLE (-5575 1200);
FORCEPROP 1 LAST BODY_TYPE PLUMBING
J 0
(-5575 1150);
DISPLAY 1.595745 (-5575 1150);
PAINT GREEN (-5575 1150);
DISPLAY INVISIBLE (-5575 1150);
FORCEPROP 1 LAST HDL_TAP TRUE
J 0
(-5250 1075);
DISPLAY 1.595745 (-5250 1075);
PAINT GREEN (-5250 1075);
DISPLAY INVISIBLE (-5250 1075);
FORCEPROP 1 LAST PATH I16
J 0
(-5577 1200);
DISPLAY 0.872340 (-5577 1200);
PAINT GREEN (-5577 1200);
DISPLAY INVISIBLE (-5577 1200);
FORCEADD TAP..6
R 2
(-2850 4150);
FORCEPROP 3 LASTPIN (-2900 4150) SIG_NAME M_E_DQS_DP<7>
J 0
(-2890 4160);
DISPLAY 0.659574 (-2890 4160);
PAINT MONO (-2890 4160);
DISPLAY INVISIBLE (-2890 4160);
FORCEPROP 1 LASTPIN (-2900 4150) BN 7
J 2
(-2848 4158);
DISPLAY 0.617021 (-2848 4158);
PAINT PINK (-2848 4158);
FORCEPROP 2 LAST CDS_LIB mstr_standard
J 0
(-2850 4150);
PAINT MONO (-2850 4150);
DISPLAY INVISIBLE (-2850 4150);
FORCEPROP 1 LAST BODY_TYPE PLUMBING
J 2
(-2850 4100);
DISPLAY 1.595745 (-2850 4100);
PAINT GREEN (-2850 4100);
DISPLAY INVISIBLE (-2850 4100);
FORCEPROP 1 LAST HDL_TAP TRUE
J 2
(-3175 4025);
DISPLAY 1.595745 (-3175 4025);
PAINT GREEN (-3175 4025);
DISPLAY INVISIBLE (-3175 4025);
FORCEPROP 1 LAST PATH I160
J 2
(-2848 4150);
DISPLAY 0.872340 (-2848 4150);
PAINT GREEN (-2848 4150);
DISPLAY INVISIBLE (-2848 4150);
FORCEADD TAP..6
R 2
(-2850 4250);
FORCEPROP 3 LASTPIN (-2900 4250) SIG_NAME M_E_DQS_DP<9>
J 0
(-2890 4260);
DISPLAY 0.659574 (-2890 4260);
PAINT MONO (-2890 4260);
DISPLAY INVISIBLE (-2890 4260);
FORCEPROP 1 LASTPIN (-2900 4250) BN 9
J 2
(-2848 4258);
DISPLAY 0.617021 (-2848 4258);
PAINT PINK (-2848 4258);
FORCEPROP 2 LAST CDS_LIB mstr_standard
J 0
(-2850 4250);
PAINT MONO (-2850 4250);
DISPLAY INVISIBLE (-2850 4250);
FORCEPROP 1 LAST BODY_TYPE PLUMBING
J 2
(-2850 4200);
DISPLAY 1.595745 (-2850 4200);
PAINT GREEN (-2850 4200);
DISPLAY INVISIBLE (-2850 4200);
FORCEPROP 1 LAST HDL_TAP TRUE
J 2
(-3175 4125);
DISPLAY 1.595745 (-3175 4125);
PAINT GREEN (-3175 4125);
DISPLAY INVISIBLE (-3175 4125);
FORCEPROP 1 LAST PATH I161
J 2
(-2848 4250);
DISPLAY 0.872340 (-2848 4250);
PAINT GREEN (-2848 4250);
DISPLAY INVISIBLE (-2848 4250);
FORCEADD TAP..6
R 2
(-2850 4200);
FORCEPROP 3 LASTPIN (-2900 4200) SIG_NAME M_E_DQS_DP<8>
J 0
(-2890 4210);
DISPLAY 0.659574 (-2890 4210);
PAINT MONO (-2890 4210);
DISPLAY INVISIBLE (-2890 4210);
FORCEPROP 1 LASTPIN (-2900 4200) BN 8
J 2
(-2848 4208);
DISPLAY 0.617021 (-2848 4208);
PAINT PINK (-2848 4208);
FORCEPROP 2 LAST CDS_LIB mstr_standard
J 0
(-2850 4200);
PAINT MONO (-2850 4200);
DISPLAY INVISIBLE (-2850 4200);
FORCEPROP 1 LAST BODY_TYPE PLUMBING
J 2
(-2850 4150);
DISPLAY 1.595745 (-2850 4150);
PAINT GREEN (-2850 4150);
DISPLAY INVISIBLE (-2850 4150);
FORCEPROP 1 LAST HDL_TAP TRUE
J 2
(-3175 4075);
DISPLAY 1.595745 (-3175 4075);
PAINT GREEN (-3175 4075);
DISPLAY INVISIBLE (-3175 4075);
FORCEPROP 1 LAST PATH I162
J 2
(-2848 4200);
DISPLAY 0.872340 (-2848 4200);
PAINT GREEN (-2848 4200);
DISPLAY INVISIBLE (-2848 4200);
FORCEADD TAP..6
R 2
(-2850 4400);
FORCEPROP 3 LASTPIN (-2900 4400) SIG_NAME M_E_DQS_DP<12>
J 0
(-2890 4410);
DISPLAY 0.659574 (-2890 4410);
PAINT MONO (-2890 4410);
DISPLAY INVISIBLE (-2890 4410);
FORCEPROP 1 LASTPIN (-2900 4400) BN 12
J 2
(-2848 4408);
DISPLAY 0.617021 (-2848 4408);
PAINT PINK (-2848 4408);
FORCEPROP 2 LAST CDS_LIB mstr_standard
J 0
(-2850 4400);
PAINT MONO (-2850 4400);
DISPLAY INVISIBLE (-2850 4400);
FORCEPROP 1 LAST BODY_TYPE PLUMBING
J 2
(-2850 4350);
DISPLAY 1.595745 (-2850 4350);
PAINT GREEN (-2850 4350);
DISPLAY INVISIBLE (-2850 4350);
FORCEPROP 1 LAST HDL_TAP TRUE
J 2
(-3175 4275);
DISPLAY 1.595745 (-3175 4275);
PAINT GREEN (-3175 4275);
DISPLAY INVISIBLE (-3175 4275);
FORCEPROP 1 LAST PATH I163
J 2
(-2848 4400);
DISPLAY 0.872340 (-2848 4400);
PAINT GREEN (-2848 4400);
DISPLAY INVISIBLE (-2848 4400);
FORCEADD TAP..6
R 2
(-2850 4350);
FORCEPROP 3 LASTPIN (-2900 4350) SIG_NAME M_E_DQS_DP<11>
J 0
(-2890 4360);
DISPLAY 0.659574 (-2890 4360);
PAINT MONO (-2890 4360);
DISPLAY INVISIBLE (-2890 4360);
FORCEPROP 1 LASTPIN (-2900 4350) BN 11
J 2
(-2848 4358);
DISPLAY 0.617021 (-2848 4358);
PAINT PINK (-2848 4358);
FORCEPROP 2 LAST CDS_LIB mstr_standard
J 0
(-2850 4350);
PAINT MONO (-2850 4350);
DISPLAY INVISIBLE (-2850 4350);
FORCEPROP 1 LAST BODY_TYPE PLUMBING
J 2
(-2850 4300);
DISPLAY 1.595745 (-2850 4300);
PAINT GREEN (-2850 4300);
DISPLAY INVISIBLE (-2850 4300);
FORCEPROP 1 LAST HDL_TAP TRUE
J 2
(-3175 4225);
DISPLAY 1.595745 (-3175 4225);
PAINT GREEN (-3175 4225);
DISPLAY INVISIBLE (-3175 4225);
FORCEPROP 1 LAST PATH I164
J 2
(-2848 4350);
DISPLAY 0.872340 (-2848 4350);
PAINT GREEN (-2848 4350);
DISPLAY INVISIBLE (-2848 4350);
FORCEADD TAP..6
R 2
(-2850 4300);
FORCEPROP 3 LASTPIN (-2900 4300) SIG_NAME M_E_DQS_DP<10>
J 0
(-2890 4310);
DISPLAY 0.659574 (-2890 4310);
PAINT MONO (-2890 4310);
DISPLAY INVISIBLE (-2890 4310);
FORCEPROP 1 LASTPIN (-2900 4300) BN 10
J 2
(-2848 4308);
DISPLAY 0.617021 (-2848 4308);
PAINT PINK (-2848 4308);
FORCEPROP 2 LAST CDS_LIB mstr_standard
J 0
(-2850 4300);
PAINT MONO (-2850 4300);
DISPLAY INVISIBLE (-2850 4300);
FORCEPROP 1 LAST BODY_TYPE PLUMBING
J 2
(-2850 4250);
DISPLAY 1.595745 (-2850 4250);
PAINT GREEN (-2850 4250);
DISPLAY INVISIBLE (-2850 4250);
FORCEPROP 1 LAST HDL_TAP TRUE
J 2
(-3175 4175);
DISPLAY 1.595745 (-3175 4175);
PAINT GREEN (-3175 4175);
DISPLAY INVISIBLE (-3175 4175);
FORCEPROP 1 LAST PATH I165
J 2
(-2848 4300);
DISPLAY 0.872340 (-2848 4300);
PAINT GREEN (-2848 4300);
DISPLAY INVISIBLE (-2848 4300);
FORCEADD TAP..6
R 2
(-2850 4450);
FORCEPROP 3 LASTPIN (-2900 4450) SIG_NAME M_E_DQS_DP<13>
J 0
(-2890 4460);
DISPLAY 0.659574 (-2890 4460);
PAINT MONO (-2890 4460);
DISPLAY INVISIBLE (-2890 4460);
FORCEPROP 1 LASTPIN (-2900 4450) BN 13
J 2
(-2848 4458);
DISPLAY 0.617021 (-2848 4458);
PAINT PINK (-2848 4458);
FORCEPROP 2 LAST CDS_LIB mstr_standard
J 0
(-2850 4450);
PAINT MONO (-2850 4450);
DISPLAY INVISIBLE (-2850 4450);
FORCEPROP 1 LAST BODY_TYPE PLUMBING
J 2
(-2850 4400);
DISPLAY 1.595745 (-2850 4400);
PAINT GREEN (-2850 4400);
DISPLAY INVISIBLE (-2850 4400);
FORCEPROP 1 LAST HDL_TAP TRUE
J 2
(-3175 4325);
DISPLAY 1.595745 (-3175 4325);
PAINT GREEN (-3175 4325);
DISPLAY INVISIBLE (-3175 4325);
FORCEPROP 1 LAST PATH I166
J 2
(-2848 4450);
DISPLAY 0.872340 (-2848 4450);
PAINT GREEN (-2848 4450);
DISPLAY INVISIBLE (-2848 4450);
FORCEADD TAP..6
R 2
(-2850 4500);
FORCEPROP 3 LASTPIN (-2900 4500) SIG_NAME M_E_DQS_DP<14>
J 0
(-2890 4510);
DISPLAY 0.659574 (-2890 4510);
PAINT MONO (-2890 4510);
DISPLAY INVISIBLE (-2890 4510);
FORCEPROP 1 LASTPIN (-2900 4500) BN 14
J 2
(-2848 4508);
DISPLAY 0.617021 (-2848 4508);
PAINT PINK (-2848 4508);
FORCEPROP 2 LAST CDS_LIB mstr_standard
J 0
(-2850 4500);
PAINT MONO (-2850 4500);
DISPLAY INVISIBLE (-2850 4500);
FORCEPROP 1 LAST BODY_TYPE PLUMBING
J 2
(-2850 4450);
DISPLAY 1.595745 (-2850 4450);
PAINT GREEN (-2850 4450);
DISPLAY INVISIBLE (-2850 4450);
FORCEPROP 1 LAST HDL_TAP TRUE
J 2
(-3175 4375);
DISPLAY 1.595745 (-3175 4375);
PAINT GREEN (-3175 4375);
DISPLAY INVISIBLE (-3175 4375);
FORCEPROP 1 LAST PATH I167
J 2
(-2848 4500);
DISPLAY 0.872340 (-2848 4500);
PAINT GREEN (-2848 4500);
DISPLAY INVISIBLE (-2848 4500);
FORCEADD TAP..6
R 2
(-2850 4550);
FORCEPROP 3 LASTPIN (-2900 4550) SIG_NAME M_E_DQS_DP<15>
J 0
(-2890 4560);
DISPLAY 0.659574 (-2890 4560);
PAINT MONO (-2890 4560);
DISPLAY INVISIBLE (-2890 4560);
FORCEPROP 1 LASTPIN (-2900 4550) BN 15
J 2
(-2848 4558);
DISPLAY 0.617021 (-2848 4558);
PAINT PINK (-2848 4558);
FORCEPROP 2 LAST CDS_LIB mstr_standard
J 0
(-2850 4550);
PAINT MONO (-2850 4550);
DISPLAY INVISIBLE (-2850 4550);
FORCEPROP 1 LAST BODY_TYPE PLUMBING
J 2
(-2850 4500);
DISPLAY 1.595745 (-2850 4500);
PAINT GREEN (-2850 4500);
DISPLAY INVISIBLE (-2850 4500);
FORCEPROP 1 LAST HDL_TAP TRUE
J 2
(-3175 4425);
DISPLAY 1.595745 (-3175 4425);
PAINT GREEN (-3175 4425);
DISPLAY INVISIBLE (-3175 4425);
FORCEPROP 1 LAST PATH I168
J 2
(-2848 4550);
DISPLAY 0.872340 (-2848 4550);
PAINT GREEN (-2848 4550);
DISPLAY INVISIBLE (-2848 4550);
FORCEADD TAP..6
R 2
(-2850 4600);
FORCEPROP 3 LASTPIN (-2900 4600) SIG_NAME M_E_DQS_DP<16>
J 0
(-2890 4610);
DISPLAY 0.659574 (-2890 4610);
PAINT MONO (-2890 4610);
DISPLAY INVISIBLE (-2890 4610);
FORCEPROP 1 LASTPIN (-2900 4600) BN 16
J 2
(-2848 4608);
DISPLAY 0.617021 (-2848 4608);
PAINT PINK (-2848 4608);
FORCEPROP 2 LAST CDS_LIB mstr_standard
J 0
(-2850 4600);
PAINT MONO (-2850 4600);
DISPLAY INVISIBLE (-2850 4600);
FORCEPROP 1 LAST BODY_TYPE PLUMBING
J 2
(-2850 4550);
DISPLAY 1.595745 (-2850 4550);
PAINT GREEN (-2850 4550);
DISPLAY INVISIBLE (-2850 4550);
FORCEPROP 1 LAST HDL_TAP TRUE
J 2
(-3175 4475);
DISPLAY 1.595745 (-3175 4475);
PAINT GREEN (-3175 4475);
DISPLAY INVISIBLE (-3175 4475);
FORCEPROP 1 LAST PATH I169
J 2
(-2848 4600);
DISPLAY 0.872340 (-2848 4600);
PAINT GREEN (-2848 4600);
DISPLAY INVISIBLE (-2848 4600);
FORCEADD TAP..6
(-5575 1250);
FORCEPROP 3 LASTPIN (-5525 1250) SIG_NAME M_E_ECC<4>
J 0
(-5515 1260);
DISPLAY 0.659574 (-5515 1260);
PAINT MONO (-5515 1260);
DISPLAY INVISIBLE (-5515 1260);
FORCEPROP 1 LASTPIN (-5525 1250) BN 4
J 0
(-5577 1258);
DISPLAY 0.617021 (-5577 1258);
PAINT PINK (-5577 1258);
FORCEPROP 2 LAST CDS_LIB mstr_standard
J 0
(-5575 1250);
PAINT MONO (-5575 1250);
DISPLAY INVISIBLE (-5575 1250);
FORCEPROP 1 LAST BODY_TYPE PLUMBING
J 0
(-5575 1200);
DISPLAY 1.595745 (-5575 1200);
PAINT GREEN (-5575 1200);
DISPLAY INVISIBLE (-5575 1200);
FORCEPROP 1 LAST HDL_TAP TRUE
J 0
(-5250 1125);
DISPLAY 1.595745 (-5250 1125);
PAINT GREEN (-5250 1125);
DISPLAY INVISIBLE (-5250 1125);
FORCEPROP 1 LAST PATH I17
J 0
(-5577 1250);
DISPLAY 0.872340 (-5577 1250);
PAINT GREEN (-5577 1250);
DISPLAY INVISIBLE (-5577 1250);
FORCEADD TAP..6
R 2
(-2850 4650);
FORCEPROP 3 LASTPIN (-2900 4650) SIG_NAME M_E_DQS_DP<17>
J 0
(-2890 4660);
DISPLAY 0.659574 (-2890 4660);
PAINT MONO (-2890 4660);
DISPLAY INVISIBLE (-2890 4660);
FORCEPROP 1 LASTPIN (-2900 4650) BN 17
J 2
(-2848 4658);
DISPLAY 0.617021 (-2848 4658);
PAINT PINK (-2848 4658);
FORCEPROP 2 LAST CDS_LIB mstr_standard
J 2
(-2850 4650);
PAINT MONO (-2850 4650);
DISPLAY INVISIBLE (-2850 4650);
FORCEPROP 1 LAST BODY_TYPE PLUMBING
J 2
(-2850 4600);
DISPLAY 1.595745 (-2850 4600);
PAINT GREEN (-2850 4600);
DISPLAY INVISIBLE (-2850 4600);
FORCEPROP 1 LAST HDL_TAP TRUE
J 2
(-3175 4525);
DISPLAY 1.595745 (-3175 4525);
PAINT GREEN (-3175 4525);
DISPLAY INVISIBLE (-3175 4525);
FORCEPROP 1 LAST PATH I170
J 2
(-2848 4650);
DISPLAY 0.872340 (-2848 4650);
PAINT GREEN (-2848 4650);
DISPLAY INVISIBLE (-2848 4650);
FORCEADD OFFPAGE..3
(-2000 4725);
FORCEPROP 2 LAST $XR0 51 
J 0
(-1786 4725);
DISPLAY 0.638298 (-1786 4725);
PAINT MONO (-1786 4725);
FORCEPROP 2 LAST $XR1 52 
J 0
(-1696 4725);
DISPLAY 0.638298 (-1696 4725);
PAINT MONO (-1696 4725);
FORCEPROP 2 LAST CDS_LIB mstr_standard
J 0
(-2000 4725);
PAINT MONO (-2000 4725);
DISPLAY INVISIBLE (-2000 4725);
FORCEPROP 1 LAST OFFPAGE TRUE
J 0
(-1675 4600);
DISPLAY 1.170213 (-1675 4600);
PAINT GREEN (-1675 4600);
DISPLAY INVISIBLE (-1675 4600);
FORCEPROP 1 LAST COMMENT_BODY TRUE
J 0
(-2050 4625);
DISPLAY 1.170213 (-2050 4625);
PAINT GREEN (-2050 4625);
DISPLAY INVISIBLE (-2050 4625);
FORCEPROP 2 LAST PATH I171
J 0
(-1800 4800);
DISPLAY 1.021277 (-1800 4800);
PAINT ORANGE (-1800 4800);
DISPLAY INVISIBLE (-1800 4800);
FORCEADD SKX_EXT_B..7
(-4175 2550);
FORCEPROP 1 LAST LOCATION U5D1
J 0
(-4975 4900);
DISPLAY 0.617021 (-4975 4900);
PAINT AQUA (-4975 4900);
FORCEPROP 1 LAST PART_NUMBER TBD
J 0
(-4975 300);
DISPLAY 0.617021 (-4975 300);
PAINT BLUE (-4975 300);
FORCEPROP 1 LAST MATERIAL IC
J 0
(-4975 4850);
DISPLAY 0.617021 (-4975 4850);
PAINT SKYBLUE (-4975 4850);
FORCEPROP 2 LASTPIN (-3325 500) $PN DV53
J 0
(-3315 510);
DISPLAY 0.617021 (-3315 510);
PAINT ORANGE (-3315 510);
FORCEPROP 2 LASTPIN (-3325 1550) $PN DM47
J 0
(-3315 1560);
DISPLAY 0.617021 (-3315 1560);
PAINT ORANGE (-3315 1560);
FORCEPROP 2 LASTPIN (-3325 1500) $PN DT49
J 0
(-3315 1510);
DISPLAY 0.617021 (-3315 1510);
PAINT ORANGE (-3315 1510);
FORCEPROP 2 LASTPIN (-3325 1450) $PN DN48
J 0
(-3315 1460);
DISPLAY 0.617021 (-3315 1460);
PAINT ORANGE (-3315 1460);
FORCEPROP 2 LASTPIN (-3325 1400) $PN DR50
J 0
(-3315 1410);
DISPLAY 0.617021 (-3315 1410);
PAINT ORANGE (-3315 1410);
FORCEPROP 2 LASTPIN (-3325 2750) $PN DR48
J 0
(-3315 2760);
DISPLAY 0.617021 (-3315 2760);
PAINT ORANGE (-3315 2760);
FORCEPROP 2 LASTPIN (-3325 2700) $PN DN52
J 0
(-3315 2710);
DISPLAY 0.617021 (-3315 2710);
PAINT ORANGE (-3315 2710);
FORCEPROP 2 LASTPIN (-3325 2650) $PN DR52
J 0
(-3315 2660);
DISPLAY 0.617021 (-3315 2660);
PAINT ORANGE (-3315 2660);
FORCEPROP 2 LASTPIN (-3325 2600) $PN DM51
J 0
(-3315 2610);
DISPLAY 0.617021 (-3315 2610);
PAINT ORANGE (-3315 2610);
FORCEPROP 2 LASTPIN (-3325 2550) $PN DT51
J 0
(-3315 2560);
DISPLAY 0.617021 (-3315 2560);
PAINT ORANGE (-3315 2560);
FORCEPROP 2 LASTPIN (-3325 2500) $PN DN60
J 0
(-3315 2510);
DISPLAY 0.617021 (-3315 2510);
PAINT ORANGE (-3315 2510);
FORCEPROP 2 LASTPIN (-3325 2450) $PN DR60
J 0
(-3315 2460);
DISPLAY 0.617021 (-3315 2460);
PAINT ORANGE (-3315 2460);
FORCEPROP 2 LASTPIN (-3325 2400) $PN DT55
J 0
(-3315 2410);
DISPLAY 0.617021 (-3315 2410);
PAINT ORANGE (-3315 2410);
FORCEPROP 2 LASTPIN (-3325 2350) $PN DV59
J 0
(-3315 2360);
DISPLAY 0.617021 (-3315 2360);
PAINT ORANGE (-3315 2360);
FORCEPROP 2 LASTPIN (-3325 2300) $PN DJ60
J 0
(-3315 2310);
DISPLAY 0.617021 (-3315 2310);
PAINT ORANGE (-3315 2310);
FORCEPROP 2 LASTPIN (-3325 2250) $PN DK61
J 0
(-3315 2260);
DISPLAY 0.617021 (-3315 2260);
PAINT ORANGE (-3315 2260);
FORCEPROP 2 LASTPIN (-3325 2200) $PN DM59
J 0
(-3315 2210);
DISPLAY 0.617021 (-3315 2210);
PAINT ORANGE (-3315 2210);
FORCEPROP 2 LASTPIN (-3325 2150) $PN DN58
J 0
(-3315 2160);
DISPLAY 0.617021 (-3315 2160);
PAINT ORANGE (-3315 2160);
FORCEPROP 2 LASTPIN (-3325 2100) $PN DT59
J 0
(-3315 2110);
DISPLAY 0.617021 (-3315 2110);
PAINT ORANGE (-3315 2110);
FORCEPROP 2 LASTPIN (-3325 2050) $PN DR58
J 0
(-3315 2060);
DISPLAY 0.617021 (-3315 2060);
PAINT ORANGE (-3315 2060);
FORCEPROP 2 LASTPIN (-3325 2000) $PN DV57
J 0
(-3315 2010);
DISPLAY 0.617021 (-3315 2010);
PAINT ORANGE (-3315 2010);
FORCEPROP 2 LASTPIN (-3325 1950) $PN DW58
J 0
(-3315 1960);
DISPLAY 0.617021 (-3315 1960);
PAINT ORANGE (-3315 1960);
FORCEPROP 2 LASTPIN (-3325 1900) $PN DW52
J 0
(-3315 1910);
DISPLAY 0.617021 (-3315 1910);
PAINT ORANGE (-3315 1910);
FORCEPROP 2 LASTPIN (-5025 1400) $PN EA66
J 2
(-5035 1410);
DISPLAY 0.617021 (-5035 1410);
PAINT ORANGE (-5035 1410);
FORCEPROP 2 LASTPIN (-5025 1350) $PN DU66
J 2
(-5035 1360);
DISPLAY 0.617021 (-5035 1360);
PAINT ORANGE (-5035 1360);
FORCEPROP 2 LASTPIN (-5025 1300) $PN DV69
J 2
(-5035 1310);
DISPLAY 0.617021 (-5035 1310);
PAINT ORANGE (-5035 1310);
FORCEPROP 2 LASTPIN (-5025 1250) $PN DU68
J 2
(-5035 1260);
DISPLAY 0.617021 (-5035 1260);
PAINT ORANGE (-5035 1260);
FORCEPROP 2 LASTPIN (-5025 1200) $PN DY65
J 2
(-5035 1210);
DISPLAY 0.617021 (-5035 1210);
PAINT ORANGE (-5035 1210);
FORCEPROP 2 LASTPIN (-5025 1150) $PN DV65
J 2
(-5035 1160);
DISPLAY 0.617021 (-5035 1160);
PAINT ORANGE (-5035 1160);
FORCEPROP 2 LASTPIN (-5025 1100) $PN EA68
J 2
(-5035 1110);
DISPLAY 0.617021 (-5035 1110);
PAINT ORANGE (-5035 1110);
FORCEPROP 2 LASTPIN (-5025 1050) $PN DY69
J 2
(-5035 1060);
DISPLAY 0.617021 (-5035 1060);
PAINT ORANGE (-5035 1060);
FORCEPROP 2 LASTPIN (-3325 4650) $PN DT67
J 0
(-3315 4660);
DISPLAY 0.617021 (-3315 4660);
PAINT ORANGE (-3315 4660);
FORCEPROP 2 LASTPIN (-3325 4600) $PN DE26
J 0
(-3315 4610);
DISPLAY 0.617021 (-3315 4610);
PAINT ORANGE (-3315 4610);
FORCEPROP 2 LASTPIN (-3325 4550) $PN DW26
J 0
(-3315 4560);
DISPLAY 0.617021 (-3315 4560);
PAINT ORANGE (-3315 4560);
FORCEPROP 2 LASTPIN (-3325 4500) $PN DW32
J 0
(-3315 4510);
DISPLAY 0.617021 (-3315 4510);
PAINT ORANGE (-3315 4510);
FORCEPROP 2 LASTPIN (-3325 4450) $PN DM41
J 0
(-3315 4460);
DISPLAY 0.617021 (-3315 4460);
PAINT ORANGE (-3315 4460);
FORCEPROP 2 LASTPIN (-3325 4400) $PN DY73
J 0
(-3315 4410);
DISPLAY 0.617021 (-3315 4410);
PAINT ORANGE (-3315 4410);
FORCEPROP 2 LASTPIN (-3325 4350) $PN DV79
J 0
(-3315 4360);
DISPLAY 0.617021 (-3315 4360);
PAINT ORANGE (-3315 4360);
FORCEPROP 2 LASTPIN (-3325 4300) $PN DD79
J 0
(-3315 4310);
DISPLAY 0.617021 (-3315 4310);
PAINT ORANGE (-3315 4310);
FORCEPROP 2 LASTPIN (-3325 4250) $PN CP79
J 0
(-3315 4260);
DISPLAY 0.617021 (-3315 4260);
PAINT ORANGE (-3315 4260);
FORCEPROP 2 LASTPIN (-3325 4200) $PN DY67
J 0
(-3315 4210);
DISPLAY 0.617021 (-3315 4210);
PAINT ORANGE (-3315 4210);
FORCEPROP 2 LASTPIN (-3325 4150) $PN DJ26
J 0
(-3315 4160);
DISPLAY 0.617021 (-3315 4160);
PAINT ORANGE (-3315 4160);
FORCEPROP 2 LASTPIN (-3325 4100) $PN EC26
J 0
(-3315 4110);
DISPLAY 0.617021 (-3315 4110);
PAINT ORANGE (-3315 4110);
FORCEPROP 2 LASTPIN (-3325 4050) $PN EC32
J 0
(-3315 4060);
DISPLAY 0.617021 (-3315 4060);
PAINT ORANGE (-3315 4060);
FORCEPROP 2 LASTPIN (-3325 4000) $PN DT41
J 0
(-3315 4010);
DISPLAY 0.617021 (-3315 4010);
PAINT ORANGE (-3315 4010);
FORCEPROP 2 LASTPIN (-3325 3950) $PN ED73
J 0
(-3315 3960);
DISPLAY 0.617021 (-3315 3960);
PAINT ORANGE (-3315 3960);
FORCEPROP 2 LASTPIN (-3325 3900) $PN EB79
J 0
(-3315 3910);
DISPLAY 0.617021 (-3315 3910);
PAINT ORANGE (-3315 3910);
FORCEPROP 2 LASTPIN (-3325 3850) $PN DB81
J 0
(-3315 3860);
DISPLAY 0.617021 (-3315 3860);
PAINT ORANGE (-3315 3860);
FORCEPROP 2 LASTPIN (-3325 3800) $PN CM81
J 0
(-3315 3810);
DISPLAY 0.617021 (-3315 3810);
PAINT ORANGE (-3315 3810);
FORCEPROP 2 LASTPIN (-3325 3700) $PN DV67
J 0
(-3315 3710);
DISPLAY 0.617021 (-3315 3710);
PAINT ORANGE (-3315 3710);
FORCEPROP 2 LASTPIN (-3325 3650) $PN DG26
J 0
(-3315 3660);
DISPLAY 0.617021 (-3315 3660);
PAINT ORANGE (-3315 3660);
FORCEPROP 2 LASTPIN (-3325 3600) $PN EA26
J 0
(-3315 3610);
DISPLAY 0.617021 (-3315 3610);
PAINT ORANGE (-3315 3610);
FORCEPROP 2 LASTPIN (-3325 3550) $PN EA32
J 0
(-3315 3560);
DISPLAY 0.617021 (-3315 3560);
PAINT ORANGE (-3315 3560);
FORCEPROP 2 LASTPIN (-3325 3500) $PN DP41
J 0
(-3315 3510);
DISPLAY 0.617021 (-3315 3510);
PAINT ORANGE (-3315 3510);
FORCEPROP 2 LASTPIN (-3325 3450) $PN EB73
J 0
(-3315 3460);
DISPLAY 0.617021 (-3315 3460);
PAINT ORANGE (-3315 3460);
FORCEPROP 2 LASTPIN (-3325 3400) $PN DY79
J 0
(-3315 3410);
DISPLAY 0.617021 (-3315 3410);
PAINT ORANGE (-3315 3410);
FORCEPROP 2 LASTPIN (-3325 3350) $PN DC80
J 0
(-3315 3360);
DISPLAY 0.617021 (-3315 3360);
PAINT ORANGE (-3315 3360);
FORCEPROP 2 LASTPIN (-3325 3300) $PN CN80
J 0
(-3315 3310);
DISPLAY 0.617021 (-3315 3310);
PAINT ORANGE (-3315 3310);
FORCEPROP 2 LASTPIN (-3325 3250) $PN EB67
J 0
(-3315 3260);
DISPLAY 0.617021 (-3315 3260);
PAINT ORANGE (-3315 3260);
FORCEPROP 2 LASTPIN (-3325 3200) $PN DL26
J 0
(-3315 3210);
DISPLAY 0.617021 (-3315 3210);
PAINT ORANGE (-3315 3210);
FORCEPROP 2 LASTPIN (-3325 3150) $PN EE26
J 0
(-3315 3160);
DISPLAY 0.617021 (-3315 3160);
PAINT ORANGE (-3315 3160);
FORCEPROP 2 LASTPIN (-3325 3100) $PN EE32
J 0
(-3315 3110);
DISPLAY 0.617021 (-3315 3110);
PAINT ORANGE (-3315 3110);
FORCEPROP 2 LASTPIN (-3325 3050) $PN DV41
J 0
(-3315 3060);
DISPLAY 0.617021 (-3315 3060);
PAINT ORANGE (-3315 3060);
FORCEPROP 2 LASTPIN (-3325 3000) $PN EF73
J 0
(-3315 3010);
DISPLAY 0.617021 (-3315 3010);
PAINT ORANGE (-3315 3010);
FORCEPROP 2 LASTPIN (-3325 2950) $PN ED79
J 0
(-3315 2960);
DISPLAY 0.617021 (-3315 2960);
PAINT ORANGE (-3315 2960);
FORCEPROP 2 LASTPIN (-3325 2900) $PN DA82
J 0
(-3315 2910);
DISPLAY 0.617021 (-3315 2910);
PAINT ORANGE (-3315 2910);
FORCEPROP 2 LASTPIN (-3325 2850) $PN CL82
J 0
(-3315 2860);
DISPLAY 0.617021 (-3315 2860);
PAINT ORANGE (-3315 2860);
FORCEPROP 2 LASTPIN (-5025 4650) $PN DK25
J 2
(-5035 4660);
DISPLAY 0.617021 (-5035 4660);
PAINT ORANGE (-5035 4660);
FORCEPROP 2 LASTPIN (-5025 4600) $PN DF25
J 2
(-5035 4610);
DISPLAY 0.617021 (-5035 4610);
PAINT ORANGE (-5035 4610);
FORCEPROP 2 LASTPIN (-5025 4550) $PN DJ28
J 2
(-5035 4560);
DISPLAY 0.617021 (-5035 4560);
PAINT ORANGE (-5035 4560);
FORCEPROP 2 LASTPIN (-5025 4500) $PN DG28
J 2
(-5035 4510);
DISPLAY 0.617021 (-5035 4510);
PAINT ORANGE (-5035 4510);
FORCEPROP 2 LASTPIN (-5025 4450) $PN DJ24
J 2
(-5035 4460);
DISPLAY 0.617021 (-5035 4460);
PAINT ORANGE (-5035 4460);
FORCEPROP 2 LASTPIN (-5025 4400) $PN DD25
J 2
(-5035 4410);
DISPLAY 0.617021 (-5035 4410);
PAINT ORANGE (-5035 4410);
FORCEPROP 2 LASTPIN (-5025 4350) $PN DK27
J 2
(-5035 4360);
DISPLAY 0.617021 (-5035 4360);
PAINT ORANGE (-5035 4360);
FORCEPROP 2 LASTPIN (-5025 4300) $PN DF27
J 2
(-5035 4310);
DISPLAY 0.617021 (-5035 4310);
PAINT ORANGE (-5035 4310);
FORCEPROP 2 LASTPIN (-5025 4250) $PN ED25
J 2
(-5035 4260);
DISPLAY 0.617021 (-5035 4260);
PAINT ORANGE (-5035 4260);
FORCEPROP 2 LASTPIN (-5025 4200) $PN DY25
J 2
(-5035 4210);
DISPLAY 0.617021 (-5035 4210);
PAINT ORANGE (-5035 4210);
FORCEPROP 2 LASTPIN (-5025 4150) $PN EA28
J 2
(-5035 4160);
DISPLAY 0.617021 (-5035 4160);
PAINT ORANGE (-5035 4160);
FORCEPROP 2 LASTPIN (-5025 4100) $PN DY27
J 2
(-5035 4110);
DISPLAY 0.617021 (-5035 4110);
PAINT ORANGE (-5035 4110);
FORCEPROP 2 LASTPIN (-5025 4050) $PN EC24
J 2
(-5035 4060);
DISPLAY 0.617021 (-5035 4060);
PAINT ORANGE (-5035 4060);
FORCEPROP 2 LASTPIN (-5025 4000) $PN EA24
J 2
(-5035 4010);
DISPLAY 0.617021 (-5035 4010);
PAINT ORANGE (-5035 4010);
FORCEPROP 2 LASTPIN (-5025 3950) $PN ED27
J 2
(-5035 3960);
DISPLAY 0.617021 (-5035 3960);
PAINT ORANGE (-5035 3960);
FORCEPROP 2 LASTPIN (-5025 3900) $PN EC28
J 2
(-5035 3910);
DISPLAY 0.617021 (-5035 3910);
PAINT ORANGE (-5035 3910);
FORCEPROP 2 LASTPIN (-5025 3850) $PN ED31
J 2
(-5035 3860);
DISPLAY 0.617021 (-5035 3860);
PAINT ORANGE (-5035 3860);
FORCEPROP 2 LASTPIN (-5025 3800) $PN DY31
J 2
(-5035 3810);
DISPLAY 0.617021 (-5035 3810);
PAINT ORANGE (-5035 3810);
FORCEPROP 2 LASTPIN (-5025 3750) $PN EA34
J 2
(-5035 3760);
DISPLAY 0.617021 (-5035 3760);
PAINT ORANGE (-5035 3760);
FORCEPROP 2 LASTPIN (-5025 3700) $PN DY33
J 2
(-5035 3710);
DISPLAY 0.617021 (-5035 3710);
PAINT ORANGE (-5035 3710);
FORCEPROP 2 LASTPIN (-5025 3650) $PN EC30
J 2
(-5035 3660);
DISPLAY 0.617021 (-5035 3660);
PAINT ORANGE (-5035 3660);
FORCEPROP 2 LASTPIN (-5025 3600) $PN EA30
J 2
(-5035 3610);
DISPLAY 0.617021 (-5035 3610);
PAINT ORANGE (-5035 3610);
FORCEPROP 2 LASTPIN (-5025 3550) $PN ED33
J 2
(-5035 3560);
DISPLAY 0.617021 (-5035 3560);
PAINT ORANGE (-5035 3560);
FORCEPROP 2 LASTPIN (-5025 3500) $PN EC34
J 2
(-5035 3510);
DISPLAY 0.617021 (-5035 3510);
PAINT ORANGE (-5035 3510);
FORCEPROP 2 LASTPIN (-5025 3450) $PN DU40
J 2
(-5035 3460);
DISPLAY 0.617021 (-5035 3460);
PAINT ORANGE (-5035 3460);
FORCEPROP 2 LASTPIN (-5025 3400) $PN DN40
J 2
(-5035 3410);
DISPLAY 0.617021 (-5035 3410);
PAINT ORANGE (-5035 3410);
FORCEPROP 2 LASTPIN (-5025 3350) $PN DN42
J 2
(-5035 3360);
DISPLAY 0.617021 (-5035 3360);
PAINT ORANGE (-5035 3360);
FORCEPROP 2 LASTPIN (-5025 3300) $PN DL42
J 2
(-5035 3310);
DISPLAY 0.617021 (-5035 3310);
PAINT ORANGE (-5035 3310);
FORCEPROP 2 LASTPIN (-5025 3250) $PN DT39
J 2
(-5035 3260);
DISPLAY 0.617021 (-5035 3260);
PAINT ORANGE (-5035 3260);
FORCEPROP 2 LASTPIN (-5025 3200) $PN DP39
J 2
(-5035 3210);
DISPLAY 0.617021 (-5035 3210);
PAINT ORANGE (-5035 3210);
FORCEPROP 2 LASTPIN (-5025 3150) $PN DW42
J 2
(-5035 3160);
DISPLAY 0.617021 (-5035 3160);
PAINT ORANGE (-5035 3160);
FORCEPROP 2 LASTPIN (-5025 3100) $PN DU42
J 2
(-5035 3110);
DISPLAY 0.617021 (-5035 3110);
PAINT ORANGE (-5035 3110);
FORCEPROP 2 LASTPIN (-5025 3050) $PN EE72
J 2
(-5035 3060);
DISPLAY 0.617021 (-5035 3060);
PAINT ORANGE (-5035 3060);
FORCEPROP 2 LASTPIN (-5025 3000) $PN EA72
J 2
(-5035 3010);
DISPLAY 0.617021 (-5035 3010);
PAINT ORANGE (-5035 3010);
FORCEPROP 2 LASTPIN (-5025 2950) $PN EB75
J 2
(-5035 2960);
DISPLAY 0.617021 (-5035 2960);
PAINT ORANGE (-5035 2960);
FORCEPROP 2 LASTPIN (-5025 2900) $PN EA74
J 2
(-5035 2910);
DISPLAY 0.617021 (-5035 2910);
PAINT ORANGE (-5035 2910);
FORCEPROP 2 LASTPIN (-5025 2850) $PN ED71
J 2
(-5035 2860);
DISPLAY 0.617021 (-5035 2860);
PAINT ORANGE (-5035 2860);
FORCEPROP 2 LASTPIN (-5025 2800) $PN EB71
J 2
(-5035 2810);
DISPLAY 0.617021 (-5035 2810);
PAINT ORANGE (-5035 2810);
FORCEPROP 2 LASTPIN (-5025 2750) $PN EE74
J 2
(-5035 2760);
DISPLAY 0.617021 (-5035 2760);
PAINT ORANGE (-5035 2760);
FORCEPROP 2 LASTPIN (-5025 2700) $PN ED75
J 2
(-5035 2710);
DISPLAY 0.617021 (-5035 2710);
PAINT ORANGE (-5035 2710);
FORCEPROP 2 LASTPIN (-5025 2650) $PN EC78
J 2
(-5035 2660);
DISPLAY 0.617021 (-5035 2660);
PAINT ORANGE (-5035 2660);
FORCEPROP 2 LASTPIN (-5025 2600) $PN DW78
J 2
(-5035 2610);
DISPLAY 0.617021 (-5035 2610);
PAINT ORANGE (-5035 2610);
FORCEPROP 2 LASTPIN (-5025 2550) $PN EB81
J 2
(-5035 2560);
DISPLAY 0.617021 (-5035 2560);
PAINT ORANGE (-5035 2560);
FORCEPROP 2 LASTPIN (-5025 2500) $PN DY81
J 2
(-5035 2510);
DISPLAY 0.617021 (-5035 2510);
PAINT ORANGE (-5035 2510);
FORCEPROP 2 LASTPIN (-5025 2450) $PN EB77
J 2
(-5035 2460);
DISPLAY 0.617021 (-5035 2460);
PAINT ORANGE (-5035 2460);
FORCEPROP 2 LASTPIN (-5025 2400) $PN DY77
J 2
(-5035 2410);
DISPLAY 0.617021 (-5035 2410);
PAINT ORANGE (-5035 2410);
FORCEPROP 2 LASTPIN (-5025 2350) $PN EC80
J 2
(-5035 2360);
DISPLAY 0.617021 (-5035 2360);
PAINT ORANGE (-5035 2360);
FORCEPROP 2 LASTPIN (-5025 2300) $PN DW80
J 2
(-5035 2310);
DISPLAY 0.617021 (-5035 2310);
PAINT ORANGE (-5035 2310);
FORCEPROP 2 LASTPIN (-5025 2250) $PN DE82
J 2
(-5035 2260);
DISPLAY 0.617021 (-5035 2260);
PAINT ORANGE (-5035 2260);
FORCEPROP 2 LASTPIN (-5025 2200) $PN DC82
J 2
(-5035 2210);
DISPLAY 0.617021 (-5035 2210);
PAINT ORANGE (-5035 2210);
FORCEPROP 2 LASTPIN (-5025 2150) $PN CW80
J 2
(-5035 2160);
DISPLAY 0.617021 (-5035 2160);
PAINT ORANGE (-5035 2160);
FORCEPROP 2 LASTPIN (-5025 2100) $PN CY79
J 2
(-5035 2110);
DISPLAY 0.617021 (-5035 2110);
PAINT ORANGE (-5035 2110);
FORCEPROP 2 LASTPIN (-5025 2050) $PN DF81
J 2
(-5035 2060);
DISPLAY 0.617021 (-5035 2060);
PAINT ORANGE (-5035 2060);
FORCEPROP 2 LASTPIN (-5025 2000) $PN DE80
J 2
(-5035 2010);
DISPLAY 0.617021 (-5035 2010);
PAINT ORANGE (-5035 2010);
FORCEPROP 2 LASTPIN (-5025 1950) $PN CY81
J 2
(-5035 1960);
DISPLAY 0.617021 (-5035 1960);
PAINT ORANGE (-5035 1960);
FORCEPROP 2 LASTPIN (-5025 1900) $PN DB79
J 2
(-5035 1910);
DISPLAY 0.617021 (-5035 1910);
PAINT ORANGE (-5035 1910);
FORCEPROP 2 LASTPIN (-5025 1850) $PN CN82
J 2
(-5035 1860);
DISPLAY 0.617021 (-5035 1860);
PAINT ORANGE (-5035 1860);
FORCEPROP 2 LASTPIN (-5025 1800) $PN CR80
J 2
(-5035 1810);
DISPLAY 0.617021 (-5035 1810);
PAINT ORANGE (-5035 1810);
FORCEPROP 2 LASTPIN (-5025 1750) $PN CJ80
J 2
(-5035 1760);
DISPLAY 0.617021 (-5035 1760);
PAINT ORANGE (-5035 1760);
FORCEPROP 2 LASTPIN (-5025 1700) $PN CK79
J 2
(-5035 1710);
DISPLAY 0.617021 (-5035 1710);
PAINT ORANGE (-5035 1710);
FORCEPROP 2 LASTPIN (-5025 1650) $PN CR82
J 2
(-5035 1660);
DISPLAY 0.617021 (-5035 1660);
PAINT ORANGE (-5035 1660);
FORCEPROP 2 LASTPIN (-5025 1600) $PN CT81
J 2
(-5035 1610);
DISPLAY 0.617021 (-5035 1610);
PAINT ORANGE (-5035 1610);
FORCEPROP 2 LASTPIN (-5025 1550) $PN CK81
J 2
(-5035 1560);
DISPLAY 0.617021 (-5035 1560);
PAINT ORANGE (-5035 1560);
FORCEPROP 2 LASTPIN (-5025 1500) $PN CM79
J 2
(-5035 1510);
DISPLAY 0.617021 (-5035 1510);
PAINT ORANGE (-5035 1510);
FORCEPROP 2 LASTPIN (-3325 1300) $PN DN46
J 0
(-3315 1310);
DISPLAY 0.617021 (-3315 1310);
PAINT ORANGE (-3315 1310);
FORCEPROP 2 LASTPIN (-3325 1250) $PN DT45
J 0
(-3315 1260);
DISPLAY 0.617021 (-3315 1260);
PAINT ORANGE (-3315 1260);
FORCEPROP 2 LASTPIN (-3325 1200) $PN DM49
J 0
(-3315 1210);
DISPLAY 0.617021 (-3315 1210);
PAINT ORANGE (-3315 1210);
FORCEPROP 2 LASTPIN (-3325 1150) $PN DW50
J 0
(-3315 1160);
DISPLAY 0.617021 (-3315 1160);
PAINT ORANGE (-3315 1160);
FORCEPROP 2 LASTPIN (-3325 1100) $PN DK47
J 0
(-3315 1110);
DISPLAY 0.617021 (-3315 1110);
PAINT ORANGE (-3315 1110);
FORCEPROP 2 LASTPIN (-3325 1050) $PN DR46
J 0
(-3315 1060);
DISPLAY 0.617021 (-3315 1060);
PAINT ORANGE (-3315 1060);
FORCEPROP 2 LASTPIN (-3325 1000) $PN DN50
J 0
(-3315 1010);
DISPLAY 0.617021 (-3315 1010);
PAINT ORANGE (-3315 1010);
FORCEPROP 2 LASTPIN (-3325 950) $PN DV51
J 0
(-3315 960);
DISPLAY 0.617021 (-3315 960);
PAINT ORANGE (-3315 960);
FORCEPROP 2 LASTPIN (-5025 950) $PN DR56
J 2
(-5035 960);
DISPLAY 0.617021 (-5035 960);
PAINT ORANGE (-5035 960);
FORCEPROP 2 LASTPIN (-5025 900) $PN DN56
J 2
(-5035 910);
DISPLAY 0.617021 (-5035 910);
PAINT ORANGE (-5035 910);
FORCEPROP 2 LASTPIN (-5025 850) $PN DT53
J 2
(-5035 860);
DISPLAY 0.617021 (-5035 860);
PAINT ORANGE (-5035 860);
FORCEPROP 2 LASTPIN (-5025 800) $PN DN54
J 2
(-5035 810);
DISPLAY 0.617021 (-5035 810);
PAINT ORANGE (-5035 810);
FORCEPROP 2 LASTPIN (-5025 750) $PN DT57
J 2
(-5035 760);
DISPLAY 0.617021 (-5035 760);
PAINT ORANGE (-5035 760);
FORCEPROP 2 LASTPIN (-5025 700) $PN DM57
J 2
(-5035 710);
DISPLAY 0.617021 (-5035 710);
PAINT ORANGE (-5035 710);
FORCEPROP 2 LASTPIN (-5025 650) $PN DR54
J 2
(-5035 660);
DISPLAY 0.617021 (-5035 660);
PAINT ORANGE (-5035 660);
FORCEPROP 2 LASTPIN (-5025 600) $PN DM55
J 2
(-5035 610);
DISPLAY 0.617021 (-5035 610);
PAINT ORANGE (-5035 610);
FORCEPROP 2 LASTPIN (-3325 1800) $PN DR64
J 0
(-3315 1810);
DISPLAY 0.617021 (-3315 1810);
PAINT ORANGE (-3315 1810);
FORCEPROP 2 LASTPIN (-3325 1750) $PN DL64
J 0
(-3315 1760);
DISPLAY 0.617021 (-3315 1760);
PAINT ORANGE (-3315 1760);
FORCEPROP 2 LASTPIN (-3325 1700) $PN DN64
J 0
(-3315 1710);
DISPLAY 0.617021 (-3315 1710);
PAINT ORANGE (-3315 1710);
FORCEPROP 2 LASTPIN (-3325 1650) $PN DM63
J 0
(-3315 1660);
DISPLAY 0.617021 (-3315 1660);
PAINT ORANGE (-3315 1660);
FORCEPROP 2 LASTPIN (-5025 500) $PN DT47
J 2
(-5035 510);
DISPLAY 0.617021 (-5035 510);
PAINT ORANGE (-5035 510);
FORCEPROP 2 LASTPIN (-3325 850) $PN DM61
J 0
(-3315 860);
DISPLAY 0.617021 (-3315 860);
PAINT ORANGE (-3315 860);
FORCEPROP 2 LASTPIN (-3325 800) $PN DJ62
J 0
(-3315 810);
DISPLAY 0.617021 (-3315 810);
PAINT ORANGE (-3315 810);
FORCEPROP 2 LASTPIN (-3325 750) $PN DV55
J 0
(-3315 760);
DISPLAY 0.617021 (-3315 760);
PAINT ORANGE (-3315 760);
FORCEPROP 2 LASTPIN (-3325 700) $PN DM53
J 0
(-3315 710);
DISPLAY 0.617021 (-3315 710);
PAINT ORANGE (-3315 710);
FORCEPROP 2 LASTPIN (-3325 550) $PN DT61
J 0
(-3315 560);
DISPLAY 0.617021 (-3315 560);
PAINT ORANGE (-3315 560);
FORCEPROP 2 LASTPIN (-3325 600) $PN DR62
J 0
(-3315 610);
DISPLAY 0.617021 (-3315 610);
PAINT ORANGE (-3315 610);
FORCEPROP 1 LAST PACK_TYPE BGA1
J 0
(-4975 4950);
PAINT SKYBLUE (-4975 4950);
DISPLAY INVISIBLE (-4975 4950);
FORCEPROP 2 LAST CDS_LIB chpset_lib
J 0
(-4175 2550);
PAINT ORANGE (-4175 2550);
DISPLAY INVISIBLE (-4175 2550);
FORCEPROP 2 LAST SEC_TYPE BGA1
J 0
(-4975 4950);
DISPLAY 1.021277 (-4975 4950);
PAINT ORANGE (-4975 4950);
DISPLAY INVISIBLE (-4975 4950);
FORCEPROP 2 LAST SEC 7
J 0
(-4975 4950);
DISPLAY 0.680851 (-4975 4950);
PAINT MONO (-4975 4950);
DISPLAY INVISIBLE (-4975 4950);
FORCEPROP 2 LAST CDS_LOCATION U5D1
J 0
(-4975 4900);
DISPLAY 0.617021 (-4975 4900);
PAINT AQUA (-4975 4900);
DISPLAY INVISIBLE (-4975 4900);
FORCEPROP 1 LAST PATH I172
J 0
(-4175 4850);
PAINT GREEN (-4175 4850);
DISPLAY INVISIBLE (-4175 4850);
FORCEPROP 0 LAST ROOM CPU0
J 0
(-4975 5000);
DISPLAY 1.021277 (-4975 5000);
PAINT ORANGE (-4975 5000);
DISPLAY INVISIBLE (-4975 5000);
FORCEADD TAP..6
(-5575 1300);
FORCEPROP 3 LASTPIN (-5525 1300) SIG_NAME M_E_ECC<5>
J 0
(-5515 1310);
DISPLAY 0.659574 (-5515 1310);
PAINT MONO (-5515 1310);
DISPLAY INVISIBLE (-5515 1310);
FORCEPROP 1 LASTPIN (-5525 1300) BN 5
J 0
(-5577 1308);
DISPLAY 0.617021 (-5577 1308);
PAINT PINK (-5577 1308);
FORCEPROP 2 LAST CDS_LIB mstr_standard
J 0
(-5575 1300);
PAINT MONO (-5575 1300);
DISPLAY INVISIBLE (-5575 1300);
FORCEPROP 1 LAST BODY_TYPE PLUMBING
J 0
(-5575 1250);
DISPLAY 1.595745 (-5575 1250);
PAINT GREEN (-5575 1250);
DISPLAY INVISIBLE (-5575 1250);
FORCEPROP 1 LAST HDL_TAP TRUE
J 0
(-5250 1175);
DISPLAY 1.595745 (-5250 1175);
PAINT GREEN (-5250 1175);
DISPLAY INVISIBLE (-5250 1175);
FORCEPROP 1 LAST PATH I18
J 0
(-5577 1300);
DISPLAY 0.872340 (-5577 1300);
PAINT GREEN (-5577 1300);
DISPLAY INVISIBLE (-5577 1300);
FORCEADD TAP..6
(-5575 1350);
FORCEPROP 3 LASTPIN (-5525 1350) SIG_NAME M_E_ECC<6>
J 0
(-5515 1360);
DISPLAY 0.659574 (-5515 1360);
PAINT MONO (-5515 1360);
DISPLAY INVISIBLE (-5515 1360);
FORCEPROP 1 LASTPIN (-5525 1350) BN 6
J 0
(-5577 1358);
DISPLAY 0.617021 (-5577 1358);
PAINT PINK (-5577 1358);
FORCEPROP 2 LAST CDS_LIB mstr_standard
J 0
(-5575 1350);
PAINT MONO (-5575 1350);
DISPLAY INVISIBLE (-5575 1350);
FORCEPROP 1 LAST BODY_TYPE PLUMBING
J 0
(-5575 1300);
DISPLAY 1.595745 (-5575 1300);
PAINT GREEN (-5575 1300);
DISPLAY INVISIBLE (-5575 1300);
FORCEPROP 1 LAST HDL_TAP TRUE
J 0
(-5250 1225);
DISPLAY 1.595745 (-5250 1225);
PAINT GREEN (-5250 1225);
DISPLAY INVISIBLE (-5250 1225);
FORCEPROP 1 LAST PATH I19
J 0
(-5577 1350);
DISPLAY 0.872340 (-5577 1350);
PAINT GREEN (-5577 1350);
DISPLAY INVISIBLE (-5577 1350);
FORCEADD OFFPAGE..5
(-6425 800);
FORCEPROP 2 LAST $XR0 51 
J 0
(-6679 800);
DISPLAY 0.638298 (-6679 800);
PAINT MONO (-6679 800);
FORCEPROP 2 LAST $XR1 52 
J 0
(-6769 800);
DISPLAY 0.638298 (-6769 800);
PAINT MONO (-6769 800);
FORCEPROP 2 LAST CDS_LIB mstr_standard
J 0
(-6425 800);
PAINT MONO (-6425 800);
DISPLAY INVISIBLE (-6425 800);
FORCEPROP 1 LAST OFFPAGE TRUE
J 0
(-6100 675);
DISPLAY 1.170213 (-6100 675);
PAINT GREEN (-6100 675);
DISPLAY INVISIBLE (-6100 675);
FORCEPROP 1 LAST COMMENT_BODY TRUE
J 0
(-6325 725);
DISPLAY 1.170213 (-6325 725);
PAINT GREEN (-6325 725);
DISPLAY INVISIBLE (-6325 725);
FORCEPROP 2 LAST PATH I2
J 0
(-6375 875);
DISPLAY 1.021277 (-6375 875);
PAINT ORANGE (-6375 875);
DISPLAY INVISIBLE (-6375 875);
FORCEADD TAP..6
(-5575 1400);
FORCEPROP 3 LASTPIN (-5525 1400) SIG_NAME M_E_ECC<7>
J 0
(-5515 1410);
DISPLAY 0.659574 (-5515 1410);
PAINT MONO (-5515 1410);
DISPLAY INVISIBLE (-5515 1410);
FORCEPROP 1 LASTPIN (-5525 1400) BN 7
J 0
(-5577 1408);
DISPLAY 0.617021 (-5577 1408);
PAINT PINK (-5577 1408);
FORCEPROP 2 LAST CDS_LIB mstr_standard
J 0
(-5575 1400);
PAINT MONO (-5575 1400);
DISPLAY INVISIBLE (-5575 1400);
FORCEPROP 1 LAST BODY_TYPE PLUMBING
J 0
(-5575 1350);
DISPLAY 1.595745 (-5575 1350);
PAINT GREEN (-5575 1350);
DISPLAY INVISIBLE (-5575 1350);
FORCEPROP 1 LAST HDL_TAP TRUE
J 0
(-5250 1275);
DISPLAY 1.595745 (-5250 1275);
PAINT GREEN (-5250 1275);
DISPLAY INVISIBLE (-5250 1275);
FORCEPROP 1 LAST PATH I20
J 0
(-5577 1400);
DISPLAY 0.872340 (-5577 1400);
PAINT GREEN (-5577 1400);
DISPLAY INVISIBLE (-5577 1400);
FORCEADD TAP..6
(-5575 1550);
FORCEPROP 3 LASTPIN (-5525 1550) SIG_NAME M_E_DQ<1>
J 0
(-5515 1560);
DISPLAY 0.659574 (-5515 1560);
PAINT MONO (-5515 1560);
DISPLAY INVISIBLE (-5515 1560);
FORCEPROP 1 LASTPIN (-5525 1550) BN 1
J 0
(-5577 1558);
DISPLAY 0.617021 (-5577 1558);
PAINT PINK (-5577 1558);
FORCEPROP 2 LAST CDS_LIB mstr_standard
J 0
(-5575 1550);
PAINT MONO (-5575 1550);
DISPLAY INVISIBLE (-5575 1550);
FORCEPROP 1 LAST BODY_TYPE PLUMBING
J 0
(-5575 1500);
DISPLAY 1.595745 (-5575 1500);
PAINT GREEN (-5575 1500);
DISPLAY INVISIBLE (-5575 1500);
FORCEPROP 1 LAST HDL_TAP TRUE
J 0
(-5250 1425);
DISPLAY 1.595745 (-5250 1425);
PAINT GREEN (-5250 1425);
DISPLAY INVISIBLE (-5250 1425);
FORCEPROP 1 LAST PATH I21
J 0
(-5577 1550);
DISPLAY 0.872340 (-5577 1550);
PAINT GREEN (-5577 1550);
DISPLAY INVISIBLE (-5577 1550);
FORCEADD TAP..6
(-5575 1500);
FORCEPROP 3 LASTPIN (-5525 1500) SIG_NAME M_E_DQ<0>
J 0
(-5515 1510);
DISPLAY 0.659574 (-5515 1510);
PAINT MONO (-5515 1510);
DISPLAY INVISIBLE (-5515 1510);
FORCEPROP 1 LASTPIN (-5525 1500) BN 0
J 0
(-5577 1508);
DISPLAY 0.617021 (-5577 1508);
PAINT PINK (-5577 1508);
FORCEPROP 2 LAST CDS_LIB mstr_standard
J 0
(-5575 1500);
PAINT MONO (-5575 1500);
DISPLAY INVISIBLE (-5575 1500);
FORCEPROP 1 LAST BODY_TYPE PLUMBING
J 0
(-5575 1450);
DISPLAY 1.595745 (-5575 1450);
PAINT GREEN (-5575 1450);
DISPLAY INVISIBLE (-5575 1450);
FORCEPROP 1 LAST HDL_TAP TRUE
J 0
(-5250 1375);
DISPLAY 1.595745 (-5250 1375);
PAINT GREEN (-5250 1375);
DISPLAY INVISIBLE (-5250 1375);
FORCEPROP 1 LAST PATH I22
J 0
(-5577 1500);
DISPLAY 0.872340 (-5577 1500);
PAINT GREEN (-5577 1500);
DISPLAY INVISIBLE (-5577 1500);
FORCEADD TAP..6
(-5575 1600);
FORCEPROP 3 LASTPIN (-5525 1600) SIG_NAME M_E_DQ<2>
J 0
(-5515 1610);
DISPLAY 0.659574 (-5515 1610);
PAINT MONO (-5515 1610);
DISPLAY INVISIBLE (-5515 1610);
FORCEPROP 1 LASTPIN (-5525 1600) BN 2
J 0
(-5577 1608);
DISPLAY 0.617021 (-5577 1608);
PAINT PINK (-5577 1608);
FORCEPROP 2 LAST CDS_LIB mstr_standard
J 0
(-5575 1600);
PAINT MONO (-5575 1600);
DISPLAY INVISIBLE (-5575 1600);
FORCEPROP 1 LAST BODY_TYPE PLUMBING
J 0
(-5575 1550);
DISPLAY 1.595745 (-5575 1550);
PAINT GREEN (-5575 1550);
DISPLAY INVISIBLE (-5575 1550);
FORCEPROP 1 LAST HDL_TAP TRUE
J 0
(-5250 1475);
DISPLAY 1.595745 (-5250 1475);
PAINT GREEN (-5250 1475);
DISPLAY INVISIBLE (-5250 1475);
FORCEPROP 1 LAST PATH I23
J 0
(-5577 1600);
DISPLAY 0.872340 (-5577 1600);
PAINT GREEN (-5577 1600);
DISPLAY INVISIBLE (-5577 1600);
FORCEADD TAP..6
(-5575 1650);
FORCEPROP 3 LASTPIN (-5525 1650) SIG_NAME M_E_DQ<3>
J 0
(-5515 1660);
DISPLAY 0.659574 (-5515 1660);
PAINT MONO (-5515 1660);
DISPLAY INVISIBLE (-5515 1660);
FORCEPROP 1 LASTPIN (-5525 1650) BN 3
J 0
(-5577 1658);
DISPLAY 0.617021 (-5577 1658);
PAINT PINK (-5577 1658);
FORCEPROP 2 LAST CDS_LIB mstr_standard
J 0
(-5575 1650);
PAINT MONO (-5575 1650);
DISPLAY INVISIBLE (-5575 1650);
FORCEPROP 1 LAST BODY_TYPE PLUMBING
J 0
(-5575 1600);
DISPLAY 1.595745 (-5575 1600);
PAINT GREEN (-5575 1600);
DISPLAY INVISIBLE (-5575 1600);
FORCEPROP 1 LAST HDL_TAP TRUE
J 0
(-5250 1525);
DISPLAY 1.595745 (-5250 1525);
PAINT GREEN (-5250 1525);
DISPLAY INVISIBLE (-5250 1525);
FORCEPROP 1 LAST PATH I24
J 0
(-5577 1650);
DISPLAY 0.872340 (-5577 1650);
PAINT GREEN (-5577 1650);
DISPLAY INVISIBLE (-5577 1650);
FORCEADD TAP..6
(-5575 1700);
FORCEPROP 3 LASTPIN (-5525 1700) SIG_NAME M_E_DQ<4>
J 0
(-5515 1710);
DISPLAY 0.659574 (-5515 1710);
PAINT MONO (-5515 1710);
DISPLAY INVISIBLE (-5515 1710);
FORCEPROP 1 LASTPIN (-5525 1700) BN 4
J 0
(-5577 1708);
DISPLAY 0.617021 (-5577 1708);
PAINT PINK (-5577 1708);
FORCEPROP 2 LAST CDS_LIB mstr_standard
J 0
(-5575 1700);
PAINT MONO (-5575 1700);
DISPLAY INVISIBLE (-5575 1700);
FORCEPROP 1 LAST BODY_TYPE PLUMBING
J 0
(-5575 1650);
DISPLAY 1.595745 (-5575 1650);
PAINT GREEN (-5575 1650);
DISPLAY INVISIBLE (-5575 1650);
FORCEPROP 1 LAST HDL_TAP TRUE
J 0
(-5250 1575);
DISPLAY 1.595745 (-5250 1575);
PAINT GREEN (-5250 1575);
DISPLAY INVISIBLE (-5250 1575);
FORCEPROP 1 LAST PATH I25
J 0
(-5577 1700);
DISPLAY 0.872340 (-5577 1700);
PAINT GREEN (-5577 1700);
DISPLAY INVISIBLE (-5577 1700);
FORCEADD TAP..6
(-5575 1750);
FORCEPROP 3 LASTPIN (-5525 1750) SIG_NAME M_E_DQ<5>
J 0
(-5515 1760);
DISPLAY 0.659574 (-5515 1760);
PAINT MONO (-5515 1760);
DISPLAY INVISIBLE (-5515 1760);
FORCEPROP 1 LASTPIN (-5525 1750) BN 5
J 0
(-5577 1758);
DISPLAY 0.617021 (-5577 1758);
PAINT PINK (-5577 1758);
FORCEPROP 2 LAST CDS_LIB mstr_standard
J 0
(-5575 1750);
PAINT MONO (-5575 1750);
DISPLAY INVISIBLE (-5575 1750);
FORCEPROP 1 LAST BODY_TYPE PLUMBING
J 0
(-5575 1700);
DISPLAY 1.595745 (-5575 1700);
PAINT GREEN (-5575 1700);
DISPLAY INVISIBLE (-5575 1700);
FORCEPROP 1 LAST HDL_TAP TRUE
J 0
(-5250 1625);
DISPLAY 1.595745 (-5250 1625);
PAINT GREEN (-5250 1625);
DISPLAY INVISIBLE (-5250 1625);
FORCEPROP 1 LAST PATH I26
J 0
(-5577 1750);
DISPLAY 0.872340 (-5577 1750);
PAINT GREEN (-5577 1750);
DISPLAY INVISIBLE (-5577 1750);
FORCEADD TAP..6
(-5575 1800);
FORCEPROP 3 LASTPIN (-5525 1800) SIG_NAME M_E_DQ<6>
J 0
(-5515 1810);
DISPLAY 0.659574 (-5515 1810);
PAINT MONO (-5515 1810);
DISPLAY INVISIBLE (-5515 1810);
FORCEPROP 1 LASTPIN (-5525 1800) BN 6
J 0
(-5577 1808);
DISPLAY 0.617021 (-5577 1808);
PAINT PINK (-5577 1808);
FORCEPROP 2 LAST CDS_LIB mstr_standard
J 0
(-5575 1800);
PAINT MONO (-5575 1800);
DISPLAY INVISIBLE (-5575 1800);
FORCEPROP 1 LAST BODY_TYPE PLUMBING
J 0
(-5575 1750);
DISPLAY 1.595745 (-5575 1750);
PAINT GREEN (-5575 1750);
DISPLAY INVISIBLE (-5575 1750);
FORCEPROP 1 LAST HDL_TAP TRUE
J 0
(-5250 1675);
DISPLAY 1.595745 (-5250 1675);
PAINT GREEN (-5250 1675);
DISPLAY INVISIBLE (-5250 1675);
FORCEPROP 1 LAST PATH I27
J 0
(-5577 1800);
DISPLAY 0.872340 (-5577 1800);
PAINT GREEN (-5577 1800);
DISPLAY INVISIBLE (-5577 1800);
FORCEADD TAP..6
(-5575 1900);
FORCEPROP 3 LASTPIN (-5525 1900) SIG_NAME M_E_DQ<8>
J 0
(-5515 1910);
DISPLAY 0.659574 (-5515 1910);
PAINT MONO (-5515 1910);
DISPLAY INVISIBLE (-5515 1910);
FORCEPROP 1 LASTPIN (-5525 1900) BN 8
J 0
(-5577 1908);
DISPLAY 0.617021 (-5577 1908);
PAINT PINK (-5577 1908);
FORCEPROP 2 LAST CDS_LIB mstr_standard
J 0
(-5575 1900);
PAINT MONO (-5575 1900);
DISPLAY INVISIBLE (-5575 1900);
FORCEPROP 1 LAST BODY_TYPE PLUMBING
J 0
(-5575 1850);
DISPLAY 1.595745 (-5575 1850);
PAINT GREEN (-5575 1850);
DISPLAY INVISIBLE (-5575 1850);
FORCEPROP 1 LAST HDL_TAP TRUE
J 0
(-5250 1775);
DISPLAY 1.595745 (-5250 1775);
PAINT GREEN (-5250 1775);
DISPLAY INVISIBLE (-5250 1775);
FORCEPROP 1 LAST PATH I28
J 0
(-5577 1900);
DISPLAY 0.872340 (-5577 1900);
PAINT GREEN (-5577 1900);
DISPLAY INVISIBLE (-5577 1900);
FORCEADD TAP..6
(-5575 1850);
FORCEPROP 3 LASTPIN (-5525 1850) SIG_NAME M_E_DQ<7>
J 0
(-5515 1860);
DISPLAY 0.659574 (-5515 1860);
PAINT MONO (-5515 1860);
DISPLAY INVISIBLE (-5515 1860);
FORCEPROP 1 LASTPIN (-5525 1850) BN 7
J 0
(-5577 1858);
DISPLAY 0.617021 (-5577 1858);
PAINT PINK (-5577 1858);
FORCEPROP 2 LAST CDS_LIB mstr_standard
J 0
(-5575 1850);
PAINT MONO (-5575 1850);
DISPLAY INVISIBLE (-5575 1850);
FORCEPROP 1 LAST BODY_TYPE PLUMBING
J 0
(-5575 1800);
DISPLAY 1.595745 (-5575 1800);
PAINT GREEN (-5575 1800);
DISPLAY INVISIBLE (-5575 1800);
FORCEPROP 1 LAST HDL_TAP TRUE
J 0
(-5250 1725);
DISPLAY 1.595745 (-5250 1725);
PAINT GREEN (-5250 1725);
DISPLAY INVISIBLE (-5250 1725);
FORCEPROP 1 LAST PATH I29
J 0
(-5577 1850);
DISPLAY 0.872340 (-5577 1850);
PAINT GREEN (-5577 1850);
DISPLAY INVISIBLE (-5577 1850);
FORCEADD OFFPAGE..5
(-6425 1000);
FORCEPROP 2 LAST $XR0 51 
J 0
(-6679 1000);
DISPLAY 0.638298 (-6679 1000);
PAINT MONO (-6679 1000);
FORCEPROP 2 LAST $XR1 52 
J 0
(-6769 1000);
DISPLAY 0.638298 (-6769 1000);
PAINT MONO (-6769 1000);
FORCEPROP 2 LAST CDS_LIB mstr_standard
J 0
(-6425 1000);
PAINT MONO (-6425 1000);
DISPLAY INVISIBLE (-6425 1000);
FORCEPROP 1 LAST OFFPAGE TRUE
J 0
(-6100 875);
DISPLAY 1.170213 (-6100 875);
PAINT GREEN (-6100 875);
DISPLAY INVISIBLE (-6100 875);
FORCEPROP 1 LAST COMMENT_BODY TRUE
J 0
(-6325 925);
DISPLAY 1.170213 (-6325 925);
PAINT GREEN (-6325 925);
DISPLAY INVISIBLE (-6325 925);
FORCEPROP 2 LAST PATH I3
J 0
(-6375 1075);
DISPLAY 1.021277 (-6375 1075);
PAINT ORANGE (-6375 1075);
DISPLAY INVISIBLE (-6375 1075);
FORCEADD TAP..6
(-5575 1950);
FORCEPROP 3 LASTPIN (-5525 1950) SIG_NAME M_E_DQ<9>
J 0
(-5515 1960);
DISPLAY 0.659574 (-5515 1960);
PAINT MONO (-5515 1960);
DISPLAY INVISIBLE (-5515 1960);
FORCEPROP 1 LASTPIN (-5525 1950) BN 9
J 0
(-5577 1958);
DISPLAY 0.617021 (-5577 1958);
PAINT PINK (-5577 1958);
FORCEPROP 2 LAST CDS_LIB mstr_standard
J 0
(-5575 1950);
PAINT MONO (-5575 1950);
DISPLAY INVISIBLE (-5575 1950);
FORCEPROP 1 LAST BODY_TYPE PLUMBING
J 0
(-5575 1900);
DISPLAY 1.595745 (-5575 1900);
PAINT GREEN (-5575 1900);
DISPLAY INVISIBLE (-5575 1900);
FORCEPROP 1 LAST HDL_TAP TRUE
J 0
(-5250 1825);
DISPLAY 1.595745 (-5250 1825);
PAINT GREEN (-5250 1825);
DISPLAY INVISIBLE (-5250 1825);
FORCEPROP 1 LAST PATH I30
J 0
(-5577 1950);
DISPLAY 0.872340 (-5577 1950);
PAINT GREEN (-5577 1950);
DISPLAY INVISIBLE (-5577 1950);
FORCEADD TAP..6
(-5575 2000);
FORCEPROP 3 LASTPIN (-5525 2000) SIG_NAME M_E_DQ<10>
J 0
(-5515 2010);
DISPLAY 0.659574 (-5515 2010);
PAINT MONO (-5515 2010);
DISPLAY INVISIBLE (-5515 2010);
FORCEPROP 1 LASTPIN (-5525 2000) BN 10
J 0
(-5577 2008);
DISPLAY 0.617021 (-5577 2008);
PAINT PINK (-5577 2008);
FORCEPROP 2 LAST CDS_LIB mstr_standard
J 0
(-5575 2000);
PAINT MONO (-5575 2000);
DISPLAY INVISIBLE (-5575 2000);
FORCEPROP 1 LAST BODY_TYPE PLUMBING
J 0
(-5575 1950);
DISPLAY 1.595745 (-5575 1950);
PAINT GREEN (-5575 1950);
DISPLAY INVISIBLE (-5575 1950);
FORCEPROP 1 LAST HDL_TAP TRUE
J 0
(-5250 1875);
DISPLAY 1.595745 (-5250 1875);
PAINT GREEN (-5250 1875);
DISPLAY INVISIBLE (-5250 1875);
FORCEPROP 1 LAST PATH I32
J 0
(-5577 2000);
DISPLAY 0.872340 (-5577 2000);
PAINT GREEN (-5577 2000);
DISPLAY INVISIBLE (-5577 2000);
FORCEADD TAP..6
(-5575 2050);
FORCEPROP 3 LASTPIN (-5525 2050) SIG_NAME M_E_DQ<11>
J 0
(-5515 2060);
DISPLAY 0.659574 (-5515 2060);
PAINT MONO (-5515 2060);
DISPLAY INVISIBLE (-5515 2060);
FORCEPROP 1 LASTPIN (-5525 2050) BN 11
J 0
(-5577 2058);
DISPLAY 0.617021 (-5577 2058);
PAINT PINK (-5577 2058);
FORCEPROP 2 LAST CDS_LIB mstr_standard
J 0
(-5575 2050);
PAINT MONO (-5575 2050);
DISPLAY INVISIBLE (-5575 2050);
FORCEPROP 1 LAST BODY_TYPE PLUMBING
J 0
(-5575 2000);
DISPLAY 1.595745 (-5575 2000);
PAINT GREEN (-5575 2000);
DISPLAY INVISIBLE (-5575 2000);
FORCEPROP 1 LAST HDL_TAP TRUE
J 0
(-5250 1925);
DISPLAY 1.595745 (-5250 1925);
PAINT GREEN (-5250 1925);
DISPLAY INVISIBLE (-5250 1925);
FORCEPROP 1 LAST PATH I33
J 0
(-5577 2050);
DISPLAY 0.872340 (-5577 2050);
PAINT GREEN (-5577 2050);
DISPLAY INVISIBLE (-5577 2050);
FORCEADD TAP..6
(-5575 2100);
FORCEPROP 3 LASTPIN (-5525 2100) SIG_NAME M_E_DQ<12>
J 0
(-5515 2110);
DISPLAY 0.659574 (-5515 2110);
PAINT MONO (-5515 2110);
DISPLAY INVISIBLE (-5515 2110);
FORCEPROP 1 LASTPIN (-5525 2100) BN 12
J 0
(-5577 2108);
DISPLAY 0.617021 (-5577 2108);
PAINT PINK (-5577 2108);
FORCEPROP 2 LAST CDS_LIB mstr_standard
J 0
(-5575 2100);
PAINT MONO (-5575 2100);
DISPLAY INVISIBLE (-5575 2100);
FORCEPROP 1 LAST BODY_TYPE PLUMBING
J 0
(-5575 2050);
DISPLAY 1.595745 (-5575 2050);
PAINT GREEN (-5575 2050);
DISPLAY INVISIBLE (-5575 2050);
FORCEPROP 1 LAST HDL_TAP TRUE
J 0
(-5250 1975);
DISPLAY 1.595745 (-5250 1975);
PAINT GREEN (-5250 1975);
DISPLAY INVISIBLE (-5250 1975);
FORCEPROP 1 LAST PATH I34
J 0
(-5577 2100);
DISPLAY 0.872340 (-5577 2100);
PAINT GREEN (-5577 2100);
DISPLAY INVISIBLE (-5577 2100);
FORCEADD TAP..6
(-5575 2150);
FORCEPROP 3 LASTPIN (-5525 2150) SIG_NAME M_E_DQ<13>
J 0
(-5515 2160);
DISPLAY 0.659574 (-5515 2160);
PAINT MONO (-5515 2160);
DISPLAY INVISIBLE (-5515 2160);
FORCEPROP 1 LASTPIN (-5525 2150) BN 13
J 0
(-5577 2158);
DISPLAY 0.617021 (-5577 2158);
PAINT PINK (-5577 2158);
FORCEPROP 2 LAST CDS_LIB mstr_standard
J 0
(-5575 2150);
PAINT MONO (-5575 2150);
DISPLAY INVISIBLE (-5575 2150);
FORCEPROP 1 LAST BODY_TYPE PLUMBING
J 0
(-5575 2100);
DISPLAY 1.595745 (-5575 2100);
PAINT GREEN (-5575 2100);
DISPLAY INVISIBLE (-5575 2100);
FORCEPROP 1 LAST HDL_TAP TRUE
J 0
(-5250 2025);
DISPLAY 1.595745 (-5250 2025);
PAINT GREEN (-5250 2025);
DISPLAY INVISIBLE (-5250 2025);
FORCEPROP 1 LAST PATH I35
J 0
(-5577 2150);
DISPLAY 0.872340 (-5577 2150);
PAINT GREEN (-5577 2150);
DISPLAY INVISIBLE (-5577 2150);
FORCEADD TAP..6
(-5575 2200);
FORCEPROP 3 LASTPIN (-5525 2200) SIG_NAME M_E_DQ<14>
J 0
(-5515 2210);
DISPLAY 0.659574 (-5515 2210);
PAINT MONO (-5515 2210);
DISPLAY INVISIBLE (-5515 2210);
FORCEPROP 1 LASTPIN (-5525 2200) BN 14
J 0
(-5577 2208);
DISPLAY 0.617021 (-5577 2208);
PAINT PINK (-5577 2208);
FORCEPROP 2 LAST CDS_LIB mstr_standard
J 0
(-5575 2200);
PAINT MONO (-5575 2200);
DISPLAY INVISIBLE (-5575 2200);
FORCEPROP 1 LAST BODY_TYPE PLUMBING
J 0
(-5575 2150);
DISPLAY 1.595745 (-5575 2150);
PAINT GREEN (-5575 2150);
DISPLAY INVISIBLE (-5575 2150);
FORCEPROP 1 LAST HDL_TAP TRUE
J 0
(-5250 2075);
DISPLAY 1.595745 (-5250 2075);
PAINT GREEN (-5250 2075);
DISPLAY INVISIBLE (-5250 2075);
FORCEPROP 1 LAST PATH I36
J 0
(-5577 2200);
DISPLAY 0.872340 (-5577 2200);
PAINT GREEN (-5577 2200);
DISPLAY INVISIBLE (-5577 2200);
FORCEADD TAP..6
(-5575 2250);
FORCEPROP 3 LASTPIN (-5525 2250) SIG_NAME M_E_DQ<15>
J 0
(-5515 2260);
DISPLAY 0.659574 (-5515 2260);
PAINT MONO (-5515 2260);
DISPLAY INVISIBLE (-5515 2260);
FORCEPROP 1 LASTPIN (-5525 2250) BN 15
J 0
(-5577 2258);
DISPLAY 0.617021 (-5577 2258);
PAINT PINK (-5577 2258);
FORCEPROP 2 LAST CDS_LIB mstr_standard
J 0
(-5575 2250);
PAINT MONO (-5575 2250);
DISPLAY INVISIBLE (-5575 2250);
FORCEPROP 1 LAST BODY_TYPE PLUMBING
J 0
(-5575 2200);
DISPLAY 1.595745 (-5575 2200);
PAINT GREEN (-5575 2200);
DISPLAY INVISIBLE (-5575 2200);
FORCEPROP 1 LAST HDL_TAP TRUE
J 0
(-5250 2125);
DISPLAY 1.595745 (-5250 2125);
PAINT GREEN (-5250 2125);
DISPLAY INVISIBLE (-5250 2125);
FORCEPROP 1 LAST PATH I37
J 0
(-5577 2250);
DISPLAY 0.872340 (-5577 2250);
PAINT GREEN (-5577 2250);
DISPLAY INVISIBLE (-5577 2250);
FORCEADD TAP..6
(-5575 2300);
FORCEPROP 3 LASTPIN (-5525 2300) SIG_NAME M_E_DQ<16>
J 0
(-5515 2310);
DISPLAY 0.659574 (-5515 2310);
PAINT MONO (-5515 2310);
DISPLAY INVISIBLE (-5515 2310);
FORCEPROP 1 LASTPIN (-5525 2300) BN 16
J 0
(-5577 2308);
DISPLAY 0.617021 (-5577 2308);
PAINT PINK (-5577 2308);
FORCEPROP 2 LAST CDS_LIB mstr_standard
J 0
(-5575 2300);
PAINT MONO (-5575 2300);
DISPLAY INVISIBLE (-5575 2300);
FORCEPROP 1 LAST BODY_TYPE PLUMBING
J 0
(-5575 2250);
DISPLAY 1.595745 (-5575 2250);
PAINT GREEN (-5575 2250);
DISPLAY INVISIBLE (-5575 2250);
FORCEPROP 1 LAST HDL_TAP TRUE
J 0
(-5250 2175);
DISPLAY 1.595745 (-5250 2175);
PAINT GREEN (-5250 2175);
DISPLAY INVISIBLE (-5250 2175);
FORCEPROP 1 LAST PATH I38
J 0
(-5577 2300);
DISPLAY 0.872340 (-5577 2300);
PAINT GREEN (-5577 2300);
DISPLAY INVISIBLE (-5577 2300);
FORCEADD TAP..6
(-5575 2350);
FORCEPROP 3 LASTPIN (-5525 2350) SIG_NAME M_E_DQ<17>
J 0
(-5515 2360);
DISPLAY 0.659574 (-5515 2360);
PAINT MONO (-5515 2360);
DISPLAY INVISIBLE (-5515 2360);
FORCEPROP 1 LASTPIN (-5525 2350) BN 17
J 0
(-5577 2358);
DISPLAY 0.617021 (-5577 2358);
PAINT PINK (-5577 2358);
FORCEPROP 2 LAST CDS_LIB mstr_standard
J 0
(-5575 2350);
PAINT MONO (-5575 2350);
DISPLAY INVISIBLE (-5575 2350);
FORCEPROP 1 LAST BODY_TYPE PLUMBING
J 0
(-5575 2300);
DISPLAY 1.595745 (-5575 2300);
PAINT GREEN (-5575 2300);
DISPLAY INVISIBLE (-5575 2300);
FORCEPROP 1 LAST HDL_TAP TRUE
J 0
(-5250 2225);
DISPLAY 1.595745 (-5250 2225);
PAINT GREEN (-5250 2225);
DISPLAY INVISIBLE (-5250 2225);
FORCEPROP 1 LAST PATH I39
J 0
(-5577 2350);
DISPLAY 0.872340 (-5577 2350);
PAINT GREEN (-5577 2350);
DISPLAY INVISIBLE (-5577 2350);
FORCEADD OFFPAGE..6
(-6425 1450);
FORCEPROP 2 LAST $XR0 51 
J 0
(-6674 1450);
DISPLAY 0.638298 (-6674 1450);
PAINT MONO (-6674 1450);
FORCEPROP 2 LAST $XR1 52 
J 0
(-6764 1450);
DISPLAY 0.638298 (-6764 1450);
PAINT MONO (-6764 1450);
FORCEPROP 2 LAST CDS_LIB mstr_standard
J 0
(-6425 1450);
PAINT MONO (-6425 1450);
DISPLAY INVISIBLE (-6425 1450);
FORCEPROP 1 LAST OFFPAGE TRUE
J 0
(-6100 1325);
DISPLAY 1.170213 (-6100 1325);
PAINT GREEN (-6100 1325);
DISPLAY INVISIBLE (-6100 1325);
FORCEPROP 1 LAST COMMENT_BODY TRUE
J 0
(-6325 1375);
DISPLAY 1.170213 (-6325 1375);
PAINT GREEN (-6325 1375);
DISPLAY INVISIBLE (-6325 1375);
FORCEPROP 2 LAST PATH I4
J 0
(-6375 1525);
DISPLAY 1.021277 (-6375 1525);
PAINT ORANGE (-6375 1525);
DISPLAY INVISIBLE (-6375 1525);
FORCEADD TAP..6
(-5575 2400);
FORCEPROP 3 LASTPIN (-5525 2400) SIG_NAME M_E_DQ<18>
J 0
(-5515 2410);
DISPLAY 0.659574 (-5515 2410);
PAINT MONO (-5515 2410);
DISPLAY INVISIBLE (-5515 2410);
FORCEPROP 1 LASTPIN (-5525 2400) BN 18
J 0
(-5577 2408);
DISPLAY 0.617021 (-5577 2408);
PAINT PINK (-5577 2408);
FORCEPROP 2 LAST CDS_LIB mstr_standard
J 0
(-5575 2400);
PAINT MONO (-5575 2400);
DISPLAY INVISIBLE (-5575 2400);
FORCEPROP 1 LAST BODY_TYPE PLUMBING
J 0
(-5575 2350);
DISPLAY 1.595745 (-5575 2350);
PAINT GREEN (-5575 2350);
DISPLAY INVISIBLE (-5575 2350);
FORCEPROP 1 LAST HDL_TAP TRUE
J 0
(-5250 2275);
DISPLAY 1.595745 (-5250 2275);
PAINT GREEN (-5250 2275);
DISPLAY INVISIBLE (-5250 2275);
FORCEPROP 1 LAST PATH I40
J 0
(-5577 2400);
DISPLAY 0.872340 (-5577 2400);
PAINT GREEN (-5577 2400);
DISPLAY INVISIBLE (-5577 2400);
FORCEADD TAP..6
(-5575 2450);
FORCEPROP 3 LASTPIN (-5525 2450) SIG_NAME M_E_DQ<19>
J 0
(-5515 2460);
DISPLAY 0.659574 (-5515 2460);
PAINT MONO (-5515 2460);
DISPLAY INVISIBLE (-5515 2460);
FORCEPROP 1 LASTPIN (-5525 2450) BN 19
J 0
(-5577 2458);
DISPLAY 0.617021 (-5577 2458);
PAINT PINK (-5577 2458);
FORCEPROP 2 LAST CDS_LIB mstr_standard
J 0
(-5575 2450);
PAINT MONO (-5575 2450);
DISPLAY INVISIBLE (-5575 2450);
FORCEPROP 1 LAST BODY_TYPE PLUMBING
J 0
(-5575 2400);
DISPLAY 1.595745 (-5575 2400);
PAINT GREEN (-5575 2400);
DISPLAY INVISIBLE (-5575 2400);
FORCEPROP 1 LAST HDL_TAP TRUE
J 0
(-5250 2325);
DISPLAY 1.595745 (-5250 2325);
PAINT GREEN (-5250 2325);
DISPLAY INVISIBLE (-5250 2325);
FORCEPROP 1 LAST PATH I41
J 0
(-5577 2450);
DISPLAY 0.872340 (-5577 2450);
PAINT GREEN (-5577 2450);
DISPLAY INVISIBLE (-5577 2450);
FORCEADD TAP..6
(-5575 2500);
FORCEPROP 3 LASTPIN (-5525 2500) SIG_NAME M_E_DQ<20>
J 0
(-5515 2510);
DISPLAY 0.659574 (-5515 2510);
PAINT MONO (-5515 2510);
DISPLAY INVISIBLE (-5515 2510);
FORCEPROP 1 LASTPIN (-5525 2500) BN 20
J 0
(-5577 2508);
DISPLAY 0.617021 (-5577 2508);
PAINT PINK (-5577 2508);
FORCEPROP 2 LAST CDS_LIB mstr_standard
J 0
(-5575 2500);
PAINT MONO (-5575 2500);
DISPLAY INVISIBLE (-5575 2500);
FORCEPROP 1 LAST BODY_TYPE PLUMBING
J 0
(-5575 2450);
DISPLAY 1.595745 (-5575 2450);
PAINT GREEN (-5575 2450);
DISPLAY INVISIBLE (-5575 2450);
FORCEPROP 1 LAST HDL_TAP TRUE
J 0
(-5250 2375);
DISPLAY 1.595745 (-5250 2375);
PAINT GREEN (-5250 2375);
DISPLAY INVISIBLE (-5250 2375);
FORCEPROP 1 LAST PATH I42
J 0
(-5577 2500);
DISPLAY 0.872340 (-5577 2500);
PAINT GREEN (-5577 2500);
DISPLAY INVISIBLE (-5577 2500);
FORCEADD TAP..6
(-5575 2550);
FORCEPROP 3 LASTPIN (-5525 2550) SIG_NAME M_E_DQ<21>
J 0
(-5515 2560);
DISPLAY 0.659574 (-5515 2560);
PAINT MONO (-5515 2560);
DISPLAY INVISIBLE (-5515 2560);
FORCEPROP 1 LASTPIN (-5525 2550) BN 21
J 0
(-5577 2558);
DISPLAY 0.617021 (-5577 2558);
PAINT PINK (-5577 2558);
FORCEPROP 2 LAST CDS_LIB mstr_standard
J 0
(-5575 2550);
PAINT MONO (-5575 2550);
DISPLAY INVISIBLE (-5575 2550);
FORCEPROP 1 LAST BODY_TYPE PLUMBING
J 0
(-5575 2500);
DISPLAY 1.595745 (-5575 2500);
PAINT GREEN (-5575 2500);
DISPLAY INVISIBLE (-5575 2500);
FORCEPROP 1 LAST HDL_TAP TRUE
J 0
(-5250 2425);
DISPLAY 1.595745 (-5250 2425);
PAINT GREEN (-5250 2425);
DISPLAY INVISIBLE (-5250 2425);
FORCEPROP 1 LAST PATH I43
J 0
(-5577 2550);
DISPLAY 0.872340 (-5577 2550);
PAINT GREEN (-5577 2550);
DISPLAY INVISIBLE (-5577 2550);
FORCEADD TAP..6
(-5575 2600);
FORCEPROP 3 LASTPIN (-5525 2600) SIG_NAME M_E_DQ<22>
J 0
(-5515 2610);
DISPLAY 0.659574 (-5515 2610);
PAINT MONO (-5515 2610);
DISPLAY INVISIBLE (-5515 2610);
FORCEPROP 1 LASTPIN (-5525 2600) BN 22
J 0
(-5577 2608);
DISPLAY 0.617021 (-5577 2608);
PAINT PINK (-5577 2608);
FORCEPROP 2 LAST CDS_LIB mstr_standard
J 0
(-5575 2600);
PAINT MONO (-5575 2600);
DISPLAY INVISIBLE (-5575 2600);
FORCEPROP 1 LAST BODY_TYPE PLUMBING
J 0
(-5575 2550);
DISPLAY 1.595745 (-5575 2550);
PAINT GREEN (-5575 2550);
DISPLAY INVISIBLE (-5575 2550);
FORCEPROP 1 LAST HDL_TAP TRUE
J 0
(-5250 2475);
DISPLAY 1.595745 (-5250 2475);
PAINT GREEN (-5250 2475);
DISPLAY INVISIBLE (-5250 2475);
FORCEPROP 1 LAST PATH I44
J 0
(-5577 2600);
DISPLAY 0.872340 (-5577 2600);
PAINT GREEN (-5577 2600);
DISPLAY INVISIBLE (-5577 2600);
FORCEADD TAP..6
(-5575 2650);
FORCEPROP 3 LASTPIN (-5525 2650) SIG_NAME M_E_DQ<23>
J 0
(-5515 2660);
DISPLAY 0.659574 (-5515 2660);
PAINT MONO (-5515 2660);
DISPLAY INVISIBLE (-5515 2660);
FORCEPROP 1 LASTPIN (-5525 2650) BN 23
J 0
(-5577 2658);
DISPLAY 0.617021 (-5577 2658);
PAINT PINK (-5577 2658);
FORCEPROP 2 LAST CDS_LIB mstr_standard
J 0
(-5575 2650);
PAINT MONO (-5575 2650);
DISPLAY INVISIBLE (-5575 2650);
FORCEPROP 1 LAST BODY_TYPE PLUMBING
J 0
(-5575 2600);
DISPLAY 1.595745 (-5575 2600);
PAINT GREEN (-5575 2600);
DISPLAY INVISIBLE (-5575 2600);
FORCEPROP 1 LAST HDL_TAP TRUE
J 0
(-5250 2525);
DISPLAY 1.595745 (-5250 2525);
PAINT GREEN (-5250 2525);
DISPLAY INVISIBLE (-5250 2525);
FORCEPROP 1 LAST PATH I45
J 0
(-5577 2650);
DISPLAY 0.872340 (-5577 2650);
PAINT GREEN (-5577 2650);
DISPLAY INVISIBLE (-5577 2650);
FORCEADD TAP..6
(-5575 2700);
FORCEPROP 3 LASTPIN (-5525 2700) SIG_NAME M_E_DQ<24>
J 0
(-5515 2710);
DISPLAY 0.659574 (-5515 2710);
PAINT MONO (-5515 2710);
DISPLAY INVISIBLE (-5515 2710);
FORCEPROP 1 LASTPIN (-5525 2700) BN 24
J 0
(-5577 2708);
DISPLAY 0.617021 (-5577 2708);
PAINT PINK (-5577 2708);
FORCEPROP 2 LAST CDS_LIB mstr_standard
J 0
(-5575 2700);
PAINT MONO (-5575 2700);
DISPLAY INVISIBLE (-5575 2700);
FORCEPROP 1 LAST BODY_TYPE PLUMBING
J 0
(-5575 2650);
DISPLAY 1.595745 (-5575 2650);
PAINT GREEN (-5575 2650);
DISPLAY INVISIBLE (-5575 2650);
FORCEPROP 1 LAST HDL_TAP TRUE
J 0
(-5250 2575);
DISPLAY 1.595745 (-5250 2575);
PAINT GREEN (-5250 2575);
DISPLAY INVISIBLE (-5250 2575);
FORCEPROP 1 LAST PATH I46
J 0
(-5577 2700);
DISPLAY 0.872340 (-5577 2700);
PAINT GREEN (-5577 2700);
DISPLAY INVISIBLE (-5577 2700);
FORCEADD TAP..6
(-5575 2800);
FORCEPROP 3 LASTPIN (-5525 2800) SIG_NAME M_E_DQ<26>
J 0
(-5515 2810);
DISPLAY 0.659574 (-5515 2810);
PAINT MONO (-5515 2810);
DISPLAY INVISIBLE (-5515 2810);
FORCEPROP 1 LASTPIN (-5525 2800) BN 26
J 0
(-5577 2808);
DISPLAY 0.617021 (-5577 2808);
PAINT PINK (-5577 2808);
FORCEPROP 2 LAST CDS_LIB mstr_standard
J 0
(-5575 2800);
PAINT MONO (-5575 2800);
DISPLAY INVISIBLE (-5575 2800);
FORCEPROP 1 LAST BODY_TYPE PLUMBING
J 0
(-5575 2750);
DISPLAY 1.595745 (-5575 2750);
PAINT GREEN (-5575 2750);
DISPLAY INVISIBLE (-5575 2750);
FORCEPROP 1 LAST HDL_TAP TRUE
J 0
(-5250 2675);
DISPLAY 1.595745 (-5250 2675);
PAINT GREEN (-5250 2675);
DISPLAY INVISIBLE (-5250 2675);
FORCEPROP 1 LAST PATH I47
J 0
(-5577 2800);
DISPLAY 0.872340 (-5577 2800);
PAINT GREEN (-5577 2800);
DISPLAY INVISIBLE (-5577 2800);
FORCEADD TAP..6
(-5575 2750);
FORCEPROP 3 LASTPIN (-5525 2750) SIG_NAME M_E_DQ<25>
J 0
(-5515 2760);
DISPLAY 0.659574 (-5515 2760);
PAINT MONO (-5515 2760);
DISPLAY INVISIBLE (-5515 2760);
FORCEPROP 1 LASTPIN (-5525 2750) BN 25
J 0
(-5577 2758);
DISPLAY 0.617021 (-5577 2758);
PAINT PINK (-5577 2758);
FORCEPROP 2 LAST CDS_LIB mstr_standard
J 0
(-5575 2750);
PAINT MONO (-5575 2750);
DISPLAY INVISIBLE (-5575 2750);
FORCEPROP 1 LAST BODY_TYPE PLUMBING
J 0
(-5575 2700);
DISPLAY 1.595745 (-5575 2700);
PAINT GREEN (-5575 2700);
DISPLAY INVISIBLE (-5575 2700);
FORCEPROP 1 LAST HDL_TAP TRUE
J 0
(-5250 2625);
DISPLAY 1.595745 (-5250 2625);
PAINT GREEN (-5250 2625);
DISPLAY INVISIBLE (-5250 2625);
FORCEPROP 1 LAST PATH I48
J 0
(-5577 2750);
DISPLAY 0.872340 (-5577 2750);
PAINT GREEN (-5577 2750);
DISPLAY INVISIBLE (-5577 2750);
FORCEADD TAP..6
(-5575 2850);
FORCEPROP 3 LASTPIN (-5525 2850) SIG_NAME M_E_DQ<27>
J 0
(-5515 2860);
DISPLAY 0.659574 (-5515 2860);
PAINT MONO (-5515 2860);
DISPLAY INVISIBLE (-5515 2860);
FORCEPROP 1 LASTPIN (-5525 2850) BN 27
J 0
(-5577 2858);
DISPLAY 0.617021 (-5577 2858);
PAINT PINK (-5577 2858);
FORCEPROP 2 LAST CDS_LIB mstr_standard
J 0
(-5575 2850);
PAINT MONO (-5575 2850);
DISPLAY INVISIBLE (-5575 2850);
FORCEPROP 1 LAST BODY_TYPE PLUMBING
J 0
(-5575 2800);
DISPLAY 1.595745 (-5575 2800);
PAINT GREEN (-5575 2800);
DISPLAY INVISIBLE (-5575 2800);
FORCEPROP 1 LAST HDL_TAP TRUE
J 0
(-5250 2725);
DISPLAY 1.595745 (-5250 2725);
PAINT GREEN (-5250 2725);
DISPLAY INVISIBLE (-5250 2725);
FORCEPROP 1 LAST PATH I49
J 0
(-5577 2850);
DISPLAY 0.872340 (-5577 2850);
PAINT GREEN (-5577 2850);
DISPLAY INVISIBLE (-5577 2850);
FORCEADD TAP..6
(-5575 600);
FORCEPROP 3 LASTPIN (-5525 600) SIG_NAME M_E_CLK_DN<0>
J 0
(-5515 610);
DISPLAY 0.659574 (-5515 610);
PAINT MONO (-5515 610);
DISPLAY INVISIBLE (-5515 610);
FORCEPROP 1 LASTPIN (-5525 600) BN 0
J 0
(-5577 608);
DISPLAY 0.617021 (-5577 608);
PAINT PINK (-5577 608);
FORCEPROP 2 LAST CDS_LIB mstr_standard
J 0
(-5575 600);
PAINT MONO (-5575 600);
DISPLAY INVISIBLE (-5575 600);
FORCEPROP 1 LAST BODY_TYPE PLUMBING
J 0
(-5575 550);
DISPLAY 1.595745 (-5575 550);
PAINT GREEN (-5575 550);
DISPLAY INVISIBLE (-5575 550);
FORCEPROP 1 LAST HDL_TAP TRUE
J 0
(-5250 475);
DISPLAY 1.595745 (-5250 475);
PAINT GREEN (-5250 475);
DISPLAY INVISIBLE (-5250 475);
FORCEPROP 1 LAST PATH I5
J 0
(-5577 600);
DISPLAY 0.872340 (-5577 600);
PAINT GREEN (-5577 600);
DISPLAY INVISIBLE (-5577 600);
FORCEADD TAP..6
(-5575 2900);
FORCEPROP 3 LASTPIN (-5525 2900) SIG_NAME M_E_DQ<28>
J 0
(-5515 2910);
DISPLAY 0.659574 (-5515 2910);
PAINT MONO (-5515 2910);
DISPLAY INVISIBLE (-5515 2910);
FORCEPROP 1 LASTPIN (-5525 2900) BN 28
J 0
(-5577 2908);
DISPLAY 0.617021 (-5577 2908);
PAINT PINK (-5577 2908);
FORCEPROP 2 LAST CDS_LIB mstr_standard
J 0
(-5575 2900);
PAINT MONO (-5575 2900);
DISPLAY INVISIBLE (-5575 2900);
FORCEPROP 1 LAST BODY_TYPE PLUMBING
J 0
(-5575 2850);
DISPLAY 1.595745 (-5575 2850);
PAINT GREEN (-5575 2850);
DISPLAY INVISIBLE (-5575 2850);
FORCEPROP 1 LAST HDL_TAP TRUE
J 0
(-5250 2775);
DISPLAY 1.595745 (-5250 2775);
PAINT GREEN (-5250 2775);
DISPLAY INVISIBLE (-5250 2775);
FORCEPROP 1 LAST PATH I50
J 0
(-5577 2900);
DISPLAY 0.872340 (-5577 2900);
PAINT GREEN (-5577 2900);
DISPLAY INVISIBLE (-5577 2900);
FORCEADD TAP..6
(-5575 2950);
FORCEPROP 3 LASTPIN (-5525 2950) SIG_NAME M_E_DQ<29>
J 0
(-5515 2960);
DISPLAY 0.659574 (-5515 2960);
PAINT MONO (-5515 2960);
DISPLAY INVISIBLE (-5515 2960);
FORCEPROP 1 LASTPIN (-5525 2950) BN 29
J 0
(-5577 2958);
DISPLAY 0.617021 (-5577 2958);
PAINT PINK (-5577 2958);
FORCEPROP 2 LAST CDS_LIB mstr_standard
J 0
(-5575 2950);
PAINT MONO (-5575 2950);
DISPLAY INVISIBLE (-5575 2950);
FORCEPROP 1 LAST BODY_TYPE PLUMBING
J 0
(-5575 2900);
DISPLAY 1.595745 (-5575 2900);
PAINT GREEN (-5575 2900);
DISPLAY INVISIBLE (-5575 2900);
FORCEPROP 1 LAST HDL_TAP TRUE
J 0
(-5250 2825);
DISPLAY 1.595745 (-5250 2825);
PAINT GREEN (-5250 2825);
DISPLAY INVISIBLE (-5250 2825);
FORCEPROP 1 LAST PATH I51
J 0
(-5577 2950);
DISPLAY 0.872340 (-5577 2950);
PAINT GREEN (-5577 2950);
DISPLAY INVISIBLE (-5577 2950);
FORCEADD TAP..6
(-5575 3050);
FORCEPROP 3 LASTPIN (-5525 3050) SIG_NAME M_E_DQ<31>
J 0
(-5515 3060);
DISPLAY 0.659574 (-5515 3060);
PAINT MONO (-5515 3060);
DISPLAY INVISIBLE (-5515 3060);
FORCEPROP 1 LASTPIN (-5525 3050) BN 31
J 0
(-5577 3058);
DISPLAY 0.617021 (-5577 3058);
PAINT PINK (-5577 3058);
FORCEPROP 2 LAST CDS_LIB mstr_standard
J 0
(-5575 3050);
PAINT MONO (-5575 3050);
DISPLAY INVISIBLE (-5575 3050);
FORCEPROP 1 LAST BODY_TYPE PLUMBING
J 0
(-5575 3000);
DISPLAY 1.595745 (-5575 3000);
PAINT GREEN (-5575 3000);
DISPLAY INVISIBLE (-5575 3000);
FORCEPROP 1 LAST HDL_TAP TRUE
J 0
(-5250 2925);
DISPLAY 1.595745 (-5250 2925);
PAINT GREEN (-5250 2925);
DISPLAY INVISIBLE (-5250 2925);
FORCEPROP 1 LAST PATH I52
J 0
(-5577 3050);
DISPLAY 0.872340 (-5577 3050);
PAINT GREEN (-5577 3050);
DISPLAY INVISIBLE (-5577 3050);
FORCEADD TAP..6
(-5575 3000);
FORCEPROP 3 LASTPIN (-5525 3000) SIG_NAME M_E_DQ<30>
J 0
(-5515 3010);
DISPLAY 0.659574 (-5515 3010);
PAINT MONO (-5515 3010);
DISPLAY INVISIBLE (-5515 3010);
FORCEPROP 1 LASTPIN (-5525 3000) BN 30
J 0
(-5577 3008);
DISPLAY 0.617021 (-5577 3008);
PAINT PINK (-5577 3008);
FORCEPROP 2 LAST CDS_LIB mstr_standard
J 0
(-5575 3000);
PAINT MONO (-5575 3000);
DISPLAY INVISIBLE (-5575 3000);
FORCEPROP 1 LAST BODY_TYPE PLUMBING
J 0
(-5575 2950);
DISPLAY 1.595745 (-5575 2950);
PAINT GREEN (-5575 2950);
DISPLAY INVISIBLE (-5575 2950);
FORCEPROP 1 LAST HDL_TAP TRUE
J 0
(-5250 2875);
DISPLAY 1.595745 (-5250 2875);
PAINT GREEN (-5250 2875);
DISPLAY INVISIBLE (-5250 2875);
FORCEPROP 1 LAST PATH I53
J 0
(-5577 3000);
DISPLAY 0.872340 (-5577 3000);
PAINT GREEN (-5577 3000);
DISPLAY INVISIBLE (-5577 3000);
FORCEADD TAP..6
(-5575 3100);
FORCEPROP 3 LASTPIN (-5525 3100) SIG_NAME M_E_DQ<32>
J 0
(-5515 3110);
DISPLAY 0.659574 (-5515 3110);
PAINT MONO (-5515 3110);
DISPLAY INVISIBLE (-5515 3110);
FORCEPROP 1 LASTPIN (-5525 3100) BN 32
J 0
(-5577 3108);
DISPLAY 0.617021 (-5577 3108);
PAINT PINK (-5577 3108);
FORCEPROP 2 LAST CDS_LIB mstr_standard
J 0
(-5575 3100);
PAINT MONO (-5575 3100);
DISPLAY INVISIBLE (-5575 3100);
FORCEPROP 1 LAST BODY_TYPE PLUMBING
J 0
(-5575 3050);
DISPLAY 1.595745 (-5575 3050);
PAINT GREEN (-5575 3050);
DISPLAY INVISIBLE (-5575 3050);
FORCEPROP 1 LAST HDL_TAP TRUE
J 0
(-5250 2975);
DISPLAY 1.595745 (-5250 2975);
PAINT GREEN (-5250 2975);
DISPLAY INVISIBLE (-5250 2975);
FORCEPROP 1 LAST PATH I54
J 0
(-5577 3100);
DISPLAY 0.872340 (-5577 3100);
PAINT GREEN (-5577 3100);
DISPLAY INVISIBLE (-5577 3100);
FORCEADD TAP..6
(-5575 3150);
FORCEPROP 3 LASTPIN (-5525 3150) SIG_NAME M_E_DQ<33>
J 0
(-5515 3160);
DISPLAY 0.659574 (-5515 3160);
PAINT MONO (-5515 3160);
DISPLAY INVISIBLE (-5515 3160);
FORCEPROP 1 LASTPIN (-5525 3150) BN 33
J 0
(-5577 3158);
DISPLAY 0.617021 (-5577 3158);
PAINT PINK (-5577 3158);
FORCEPROP 2 LAST CDS_LIB mstr_standard
J 0
(-5575 3150);
PAINT MONO (-5575 3150);
DISPLAY INVISIBLE (-5575 3150);
FORCEPROP 1 LAST BODY_TYPE PLUMBING
J 0
(-5575 3100);
DISPLAY 1.595745 (-5575 3100);
PAINT GREEN (-5575 3100);
DISPLAY INVISIBLE (-5575 3100);
FORCEPROP 1 LAST HDL_TAP TRUE
J 0
(-5250 3025);
DISPLAY 1.595745 (-5250 3025);
PAINT GREEN (-5250 3025);
DISPLAY INVISIBLE (-5250 3025);
FORCEPROP 1 LAST PATH I55
J 0
(-5577 3150);
DISPLAY 0.872340 (-5577 3150);
PAINT GREEN (-5577 3150);
DISPLAY INVISIBLE (-5577 3150);
FORCEADD TAP..6
(-5575 3200);
FORCEPROP 3 LASTPIN (-5525 3200) SIG_NAME M_E_DQ<34>
J 0
(-5515 3210);
DISPLAY 0.659574 (-5515 3210);
PAINT MONO (-5515 3210);
DISPLAY INVISIBLE (-5515 3210);
FORCEPROP 1 LASTPIN (-5525 3200) BN 34
J 0
(-5577 3208);
DISPLAY 0.617021 (-5577 3208);
PAINT PINK (-5577 3208);
FORCEPROP 2 LAST CDS_LIB mstr_standard
J 0
(-5575 3200);
PAINT MONO (-5575 3200);
DISPLAY INVISIBLE (-5575 3200);
FORCEPROP 1 LAST BODY_TYPE PLUMBING
J 0
(-5575 3150);
DISPLAY 1.595745 (-5575 3150);
PAINT GREEN (-5575 3150);
DISPLAY INVISIBLE (-5575 3150);
FORCEPROP 1 LAST HDL_TAP TRUE
J 0
(-5250 3075);
DISPLAY 1.595745 (-5250 3075);
PAINT GREEN (-5250 3075);
DISPLAY INVISIBLE (-5250 3075);
FORCEPROP 1 LAST PATH I56
J 0
(-5577 3200);
DISPLAY 0.872340 (-5577 3200);
PAINT GREEN (-5577 3200);
DISPLAY INVISIBLE (-5577 3200);
FORCEADD TAP..6
(-5575 3250);
FORCEPROP 3 LASTPIN (-5525 3250) SIG_NAME M_E_DQ<35>
J 0
(-5515 3260);
DISPLAY 0.659574 (-5515 3260);
PAINT MONO (-5515 3260);
DISPLAY INVISIBLE (-5515 3260);
FORCEPROP 1 LASTPIN (-5525 3250) BN 35
J 0
(-5577 3258);
DISPLAY 0.617021 (-5577 3258);
PAINT PINK (-5577 3258);
FORCEPROP 2 LAST CDS_LIB mstr_standard
J 0
(-5575 3250);
PAINT MONO (-5575 3250);
DISPLAY INVISIBLE (-5575 3250);
FORCEPROP 1 LAST BODY_TYPE PLUMBING
J 0
(-5575 3200);
DISPLAY 1.595745 (-5575 3200);
PAINT GREEN (-5575 3200);
DISPLAY INVISIBLE (-5575 3200);
FORCEPROP 1 LAST HDL_TAP TRUE
J 0
(-5250 3125);
DISPLAY 1.595745 (-5250 3125);
PAINT GREEN (-5250 3125);
DISPLAY INVISIBLE (-5250 3125);
FORCEPROP 1 LAST PATH I57
J 0
(-5577 3250);
DISPLAY 0.872340 (-5577 3250);
PAINT GREEN (-5577 3250);
DISPLAY INVISIBLE (-5577 3250);
FORCEADD TAP..6
(-5575 3300);
FORCEPROP 3 LASTPIN (-5525 3300) SIG_NAME M_E_DQ<36>
J 0
(-5515 3310);
DISPLAY 0.659574 (-5515 3310);
PAINT MONO (-5515 3310);
DISPLAY INVISIBLE (-5515 3310);
FORCEPROP 1 LASTPIN (-5525 3300) BN 36
J 0
(-5577 3308);
DISPLAY 0.617021 (-5577 3308);
PAINT PINK (-5577 3308);
FORCEPROP 2 LAST CDS_LIB mstr_standard
J 0
(-5575 3300);
PAINT MONO (-5575 3300);
DISPLAY INVISIBLE (-5575 3300);
FORCEPROP 1 LAST BODY_TYPE PLUMBING
J 0
(-5575 3250);
DISPLAY 1.595745 (-5575 3250);
PAINT GREEN (-5575 3250);
DISPLAY INVISIBLE (-5575 3250);
FORCEPROP 1 LAST HDL_TAP TRUE
J 0
(-5250 3175);
DISPLAY 1.595745 (-5250 3175);
PAINT GREEN (-5250 3175);
DISPLAY INVISIBLE (-5250 3175);
FORCEPROP 1 LAST PATH I58
J 0
(-5577 3300);
DISPLAY 0.872340 (-5577 3300);
PAINT GREEN (-5577 3300);
DISPLAY INVISIBLE (-5577 3300);
FORCEADD TAP..6
(-5575 3350);
FORCEPROP 3 LASTPIN (-5525 3350) SIG_NAME M_E_DQ<37>
J 0
(-5515 3360);
DISPLAY 0.659574 (-5515 3360);
PAINT MONO (-5515 3360);
DISPLAY INVISIBLE (-5515 3360);
FORCEPROP 1 LASTPIN (-5525 3350) BN 37
J 0
(-5577 3358);
DISPLAY 0.617021 (-5577 3358);
PAINT PINK (-5577 3358);
FORCEPROP 2 LAST CDS_LIB mstr_standard
J 0
(-5575 3350);
PAINT MONO (-5575 3350);
DISPLAY INVISIBLE (-5575 3350);
FORCEPROP 1 LAST BODY_TYPE PLUMBING
J 0
(-5575 3300);
DISPLAY 1.595745 (-5575 3300);
PAINT GREEN (-5575 3300);
DISPLAY INVISIBLE (-5575 3300);
FORCEPROP 1 LAST HDL_TAP TRUE
J 0
(-5250 3225);
DISPLAY 1.595745 (-5250 3225);
PAINT GREEN (-5250 3225);
DISPLAY INVISIBLE (-5250 3225);
FORCEPROP 1 LAST PATH I59
J 0
(-5577 3350);
DISPLAY 0.872340 (-5577 3350);
PAINT GREEN (-5577 3350);
DISPLAY INVISIBLE (-5577 3350);
FORCEADD TAP..6
(-5575 650);
FORCEPROP 3 LASTPIN (-5525 650) SIG_NAME M_E_CLK_DN<1>
J 0
(-5515 660);
DISPLAY 0.659574 (-5515 660);
PAINT MONO (-5515 660);
DISPLAY INVISIBLE (-5515 660);
FORCEPROP 1 LASTPIN (-5525 650) BN 1
J 0
(-5577 658);
DISPLAY 0.617021 (-5577 658);
PAINT PINK (-5577 658);
FORCEPROP 2 LAST CDS_LIB mstr_standard
J 0
(-5575 650);
PAINT MONO (-5575 650);
DISPLAY INVISIBLE (-5575 650);
FORCEPROP 1 LAST BODY_TYPE PLUMBING
J 0
(-5575 600);
DISPLAY 1.595745 (-5575 600);
PAINT GREEN (-5575 600);
DISPLAY INVISIBLE (-5575 600);
FORCEPROP 1 LAST HDL_TAP TRUE
J 0
(-5250 525);
DISPLAY 1.595745 (-5250 525);
PAINT GREEN (-5250 525);
DISPLAY INVISIBLE (-5250 525);
FORCEPROP 1 LAST PATH I6
J 0
(-5577 650);
DISPLAY 0.872340 (-5577 650);
PAINT GREEN (-5577 650);
DISPLAY INVISIBLE (-5577 650);
FORCEADD TAP..6
(-5575 3400);
FORCEPROP 3 LASTPIN (-5525 3400) SIG_NAME M_E_DQ<38>
J 0
(-5515 3410);
DISPLAY 0.659574 (-5515 3410);
PAINT MONO (-5515 3410);
DISPLAY INVISIBLE (-5515 3410);
FORCEPROP 1 LASTPIN (-5525 3400) BN 38
J 0
(-5577 3408);
DISPLAY 0.617021 (-5577 3408);
PAINT PINK (-5577 3408);
FORCEPROP 2 LAST CDS_LIB mstr_standard
J 0
(-5575 3400);
PAINT MONO (-5575 3400);
DISPLAY INVISIBLE (-5575 3400);
FORCEPROP 1 LAST BODY_TYPE PLUMBING
J 0
(-5575 3350);
DISPLAY 1.595745 (-5575 3350);
PAINT GREEN (-5575 3350);
DISPLAY INVISIBLE (-5575 3350);
FORCEPROP 1 LAST HDL_TAP TRUE
J 0
(-5250 3275);
DISPLAY 1.595745 (-5250 3275);
PAINT GREEN (-5250 3275);
DISPLAY INVISIBLE (-5250 3275);
FORCEPROP 1 LAST PATH I60
J 0
(-5577 3400);
DISPLAY 0.872340 (-5577 3400);
PAINT GREEN (-5577 3400);
DISPLAY INVISIBLE (-5577 3400);
FORCEADD TAP..6
(-5575 3450);
FORCEPROP 3 LASTPIN (-5525 3450) SIG_NAME M_E_DQ<39>
J 0
(-5515 3460);
DISPLAY 0.659574 (-5515 3460);
PAINT MONO (-5515 3460);
DISPLAY INVISIBLE (-5515 3460);
FORCEPROP 1 LASTPIN (-5525 3450) BN 39
J 0
(-5577 3458);
DISPLAY 0.617021 (-5577 3458);
PAINT PINK (-5577 3458);
FORCEPROP 2 LAST CDS_LIB mstr_standard
J 0
(-5575 3450);
PAINT MONO (-5575 3450);
DISPLAY INVISIBLE (-5575 3450);
FORCEPROP 1 LAST BODY_TYPE PLUMBING
J 0
(-5575 3400);
DISPLAY 1.595745 (-5575 3400);
PAINT GREEN (-5575 3400);
DISPLAY INVISIBLE (-5575 3400);
FORCEPROP 1 LAST HDL_TAP TRUE
J 0
(-5250 3325);
DISPLAY 1.595745 (-5250 3325);
PAINT GREEN (-5250 3325);
DISPLAY INVISIBLE (-5250 3325);
FORCEPROP 1 LAST PATH I61
J 0
(-5577 3450);
DISPLAY 0.872340 (-5577 3450);
PAINT GREEN (-5577 3450);
DISPLAY INVISIBLE (-5577 3450);
FORCEADD TAP..6
(-5575 3500);
FORCEPROP 3 LASTPIN (-5525 3500) SIG_NAME M_E_DQ<40>
J 0
(-5515 3510);
DISPLAY 0.659574 (-5515 3510);
PAINT MONO (-5515 3510);
DISPLAY INVISIBLE (-5515 3510);
FORCEPROP 1 LASTPIN (-5525 3500) BN 40
J 0
(-5577 3508);
DISPLAY 0.617021 (-5577 3508);
PAINT PINK (-5577 3508);
FORCEPROP 2 LAST CDS_LIB mstr_standard
J 0
(-5575 3500);
PAINT MONO (-5575 3500);
DISPLAY INVISIBLE (-5575 3500);
FORCEPROP 1 LAST BODY_TYPE PLUMBING
J 0
(-5575 3450);
DISPLAY 1.595745 (-5575 3450);
PAINT GREEN (-5575 3450);
DISPLAY INVISIBLE (-5575 3450);
FORCEPROP 1 LAST HDL_TAP TRUE
J 0
(-5250 3375);
DISPLAY 1.595745 (-5250 3375);
PAINT GREEN (-5250 3375);
DISPLAY INVISIBLE (-5250 3375);
FORCEPROP 1 LAST PATH I62
J 0
(-5577 3500);
DISPLAY 0.872340 (-5577 3500);
PAINT GREEN (-5577 3500);
DISPLAY INVISIBLE (-5577 3500);
FORCEADD TAP..6
(-5575 3550);
FORCEPROP 3 LASTPIN (-5525 3550) SIG_NAME M_E_DQ<41>
J 0
(-5515 3560);
DISPLAY 0.659574 (-5515 3560);
PAINT MONO (-5515 3560);
DISPLAY INVISIBLE (-5515 3560);
FORCEPROP 1 LASTPIN (-5525 3550) BN 41
J 0
(-5577 3558);
DISPLAY 0.617021 (-5577 3558);
PAINT PINK (-5577 3558);
FORCEPROP 2 LAST CDS_LIB mstr_standard
J 0
(-5575 3550);
PAINT MONO (-5575 3550);
DISPLAY INVISIBLE (-5575 3550);
FORCEPROP 1 LAST BODY_TYPE PLUMBING
J 0
(-5575 3500);
DISPLAY 1.595745 (-5575 3500);
PAINT GREEN (-5575 3500);
DISPLAY INVISIBLE (-5575 3500);
FORCEPROP 1 LAST HDL_TAP TRUE
J 0
(-5250 3425);
DISPLAY 1.595745 (-5250 3425);
PAINT GREEN (-5250 3425);
DISPLAY INVISIBLE (-5250 3425);
FORCEPROP 1 LAST PATH I63
J 0
(-5577 3550);
DISPLAY 0.872340 (-5577 3550);
PAINT GREEN (-5577 3550);
DISPLAY INVISIBLE (-5577 3550);
FORCEADD TAP..6
(-5575 3600);
FORCEPROP 3 LASTPIN (-5525 3600) SIG_NAME M_E_DQ<42>
J 0
(-5515 3610);
DISPLAY 0.659574 (-5515 3610);
PAINT MONO (-5515 3610);
DISPLAY INVISIBLE (-5515 3610);
FORCEPROP 1 LASTPIN (-5525 3600) BN 42
J 0
(-5577 3608);
DISPLAY 0.617021 (-5577 3608);
PAINT PINK (-5577 3608);
FORCEPROP 2 LAST CDS_LIB mstr_standard
J 0
(-5575 3600);
PAINT MONO (-5575 3600);
DISPLAY INVISIBLE (-5575 3600);
FORCEPROP 1 LAST BODY_TYPE PLUMBING
J 0
(-5575 3550);
DISPLAY 1.595745 (-5575 3550);
PAINT GREEN (-5575 3550);
DISPLAY INVISIBLE (-5575 3550);
FORCEPROP 1 LAST HDL_TAP TRUE
J 0
(-5250 3475);
DISPLAY 1.595745 (-5250 3475);
PAINT GREEN (-5250 3475);
DISPLAY INVISIBLE (-5250 3475);
FORCEPROP 1 LAST PATH I64
J 0
(-5577 3600);
DISPLAY 0.872340 (-5577 3600);
PAINT GREEN (-5577 3600);
DISPLAY INVISIBLE (-5577 3600);
FORCEADD TAP..6
(-5575 3650);
FORCEPROP 3 LASTPIN (-5525 3650) SIG_NAME M_E_DQ<43>
J 0
(-5515 3660);
DISPLAY 0.659574 (-5515 3660);
PAINT MONO (-5515 3660);
DISPLAY INVISIBLE (-5515 3660);
FORCEPROP 1 LASTPIN (-5525 3650) BN 43
J 0
(-5577 3658);
DISPLAY 0.617021 (-5577 3658);
PAINT PINK (-5577 3658);
FORCEPROP 2 LAST CDS_LIB mstr_standard
J 0
(-5575 3650);
PAINT MONO (-5575 3650);
DISPLAY INVISIBLE (-5575 3650);
FORCEPROP 1 LAST BODY_TYPE PLUMBING
J 0
(-5575 3600);
DISPLAY 1.595745 (-5575 3600);
PAINT GREEN (-5575 3600);
DISPLAY INVISIBLE (-5575 3600);
FORCEPROP 1 LAST HDL_TAP TRUE
J 0
(-5250 3525);
DISPLAY 1.595745 (-5250 3525);
PAINT GREEN (-5250 3525);
DISPLAY INVISIBLE (-5250 3525);
FORCEPROP 1 LAST PATH I65
J 0
(-5577 3650);
DISPLAY 0.872340 (-5577 3650);
PAINT GREEN (-5577 3650);
DISPLAY INVISIBLE (-5577 3650);
FORCEADD TAP..6
(-5575 3700);
FORCEPROP 3 LASTPIN (-5525 3700) SIG_NAME M_E_DQ<44>
J 0
(-5515 3710);
DISPLAY 0.659574 (-5515 3710);
PAINT MONO (-5515 3710);
DISPLAY INVISIBLE (-5515 3710);
FORCEPROP 1 LASTPIN (-5525 3700) BN 44
J 0
(-5577 3708);
DISPLAY 0.617021 (-5577 3708);
PAINT PINK (-5577 3708);
FORCEPROP 2 LAST CDS_LIB mstr_standard
J 0
(-5575 3700);
PAINT MONO (-5575 3700);
DISPLAY INVISIBLE (-5575 3700);
FORCEPROP 1 LAST BODY_TYPE PLUMBING
J 0
(-5575 3650);
DISPLAY 1.595745 (-5575 3650);
PAINT GREEN (-5575 3650);
DISPLAY INVISIBLE (-5575 3650);
FORCEPROP 1 LAST HDL_TAP TRUE
J 0
(-5250 3575);
DISPLAY 1.595745 (-5250 3575);
PAINT GREEN (-5250 3575);
DISPLAY INVISIBLE (-5250 3575);
FORCEPROP 1 LAST PATH I66
J 0
(-5577 3700);
DISPLAY 0.872340 (-5577 3700);
PAINT GREEN (-5577 3700);
DISPLAY INVISIBLE (-5577 3700);
FORCEADD TAP..6
(-5575 3750);
FORCEPROP 3 LASTPIN (-5525 3750) SIG_NAME M_E_DQ<45>
J 0
(-5515 3760);
DISPLAY 0.659574 (-5515 3760);
PAINT MONO (-5515 3760);
DISPLAY INVISIBLE (-5515 3760);
FORCEPROP 1 LASTPIN (-5525 3750) BN 45
J 0
(-5577 3758);
DISPLAY 0.617021 (-5577 3758);
PAINT PINK (-5577 3758);
FORCEPROP 2 LAST CDS_LIB mstr_standard
J 0
(-5575 3750);
PAINT MONO (-5575 3750);
DISPLAY INVISIBLE (-5575 3750);
FORCEPROP 1 LAST BODY_TYPE PLUMBING
J 0
(-5575 3700);
DISPLAY 1.595745 (-5575 3700);
PAINT GREEN (-5575 3700);
DISPLAY INVISIBLE (-5575 3700);
FORCEPROP 1 LAST HDL_TAP TRUE
J 0
(-5250 3625);
DISPLAY 1.595745 (-5250 3625);
PAINT GREEN (-5250 3625);
DISPLAY INVISIBLE (-5250 3625);
FORCEPROP 1 LAST PATH I67
J 0
(-5577 3750);
DISPLAY 0.872340 (-5577 3750);
PAINT GREEN (-5577 3750);
DISPLAY INVISIBLE (-5577 3750);
FORCEADD TAP..6
(-5575 3800);
FORCEPROP 3 LASTPIN (-5525 3800) SIG_NAME M_E_DQ<46>
J 0
(-5515 3810);
DISPLAY 0.659574 (-5515 3810);
PAINT MONO (-5515 3810);
DISPLAY INVISIBLE (-5515 3810);
FORCEPROP 1 LASTPIN (-5525 3800) BN 46
J 0
(-5577 3808);
DISPLAY 0.617021 (-5577 3808);
PAINT PINK (-5577 3808);
FORCEPROP 2 LAST CDS_LIB mstr_standard
J 0
(-5575 3800);
PAINT MONO (-5575 3800);
DISPLAY INVISIBLE (-5575 3800);
FORCEPROP 1 LAST BODY_TYPE PLUMBING
J 0
(-5575 3750);
DISPLAY 1.595745 (-5575 3750);
PAINT GREEN (-5575 3750);
DISPLAY INVISIBLE (-5575 3750);
FORCEPROP 1 LAST HDL_TAP TRUE
J 0
(-5250 3675);
DISPLAY 1.595745 (-5250 3675);
PAINT GREEN (-5250 3675);
DISPLAY INVISIBLE (-5250 3675);
FORCEPROP 1 LAST PATH I68
J 0
(-5577 3800);
DISPLAY 0.872340 (-5577 3800);
PAINT GREEN (-5577 3800);
DISPLAY INVISIBLE (-5577 3800);
FORCEADD TAP..6
(-5575 3850);
FORCEPROP 3 LASTPIN (-5525 3850) SIG_NAME M_E_DQ<47>
J 0
(-5515 3860);
DISPLAY 0.659574 (-5515 3860);
PAINT MONO (-5515 3860);
DISPLAY INVISIBLE (-5515 3860);
FORCEPROP 1 LASTPIN (-5525 3850) BN 47
J 0
(-5577 3858);
DISPLAY 0.617021 (-5577 3858);
PAINT PINK (-5577 3858);
FORCEPROP 2 LAST CDS_LIB mstr_standard
J 0
(-5575 3850);
PAINT MONO (-5575 3850);
DISPLAY INVISIBLE (-5575 3850);
FORCEPROP 1 LAST BODY_TYPE PLUMBING
J 0
(-5575 3800);
DISPLAY 1.595745 (-5575 3800);
PAINT GREEN (-5575 3800);
DISPLAY INVISIBLE (-5575 3800);
FORCEPROP 1 LAST HDL_TAP TRUE
J 0
(-5250 3725);
DISPLAY 1.595745 (-5250 3725);
PAINT GREEN (-5250 3725);
DISPLAY INVISIBLE (-5250 3725);
FORCEPROP 1 LAST PATH I69
J 0
(-5577 3850);
DISPLAY 0.872340 (-5577 3850);
PAINT GREEN (-5577 3850);
DISPLAY INVISIBLE (-5577 3850);
FORCEADD TAP..6
(-5575 750);
FORCEPROP 3 LASTPIN (-5525 750) SIG_NAME M_E_CLK_DN<3>
J 0
(-5515 760);
DISPLAY 0.659574 (-5515 760);
PAINT MONO (-5515 760);
DISPLAY INVISIBLE (-5515 760);
FORCEPROP 1 LASTPIN (-5525 750) BN 3
J 0
(-5577 758);
DISPLAY 0.617021 (-5577 758);
PAINT PINK (-5577 758);
FORCEPROP 2 LAST CDS_LIB mstr_standard
J 0
(-5575 750);
PAINT MONO (-5575 750);
DISPLAY INVISIBLE (-5575 750);
FORCEPROP 1 LAST BODY_TYPE PLUMBING
J 0
(-5575 700);
DISPLAY 1.595745 (-5575 700);
PAINT GREEN (-5575 700);
DISPLAY INVISIBLE (-5575 700);
FORCEPROP 1 LAST HDL_TAP TRUE
J 0
(-5250 625);
DISPLAY 1.595745 (-5250 625);
PAINT GREEN (-5250 625);
DISPLAY INVISIBLE (-5250 625);
FORCEPROP 1 LAST PATH I7
J 0
(-5577 750);
DISPLAY 0.872340 (-5577 750);
PAINT GREEN (-5577 750);
DISPLAY INVISIBLE (-5577 750);
FORCEADD TAP..6
(-5575 3900);
FORCEPROP 3 LASTPIN (-5525 3900) SIG_NAME M_E_DQ<48>
J 0
(-5515 3910);
DISPLAY 0.659574 (-5515 3910);
PAINT MONO (-5515 3910);
DISPLAY INVISIBLE (-5515 3910);
FORCEPROP 1 LASTPIN (-5525 3900) BN 48
J 0
(-5577 3908);
DISPLAY 0.617021 (-5577 3908);
PAINT PINK (-5577 3908);
FORCEPROP 2 LAST CDS_LIB mstr_standard
J 0
(-5575 3900);
PAINT MONO (-5575 3900);
DISPLAY INVISIBLE (-5575 3900);
FORCEPROP 1 LAST BODY_TYPE PLUMBING
J 0
(-5575 3850);
DISPLAY 1.595745 (-5575 3850);
PAINT GREEN (-5575 3850);
DISPLAY INVISIBLE (-5575 3850);
FORCEPROP 1 LAST HDL_TAP TRUE
J 0
(-5250 3775);
DISPLAY 1.595745 (-5250 3775);
PAINT GREEN (-5250 3775);
DISPLAY INVISIBLE (-5250 3775);
FORCEPROP 1 LAST PATH I70
J 0
(-5577 3900);
DISPLAY 0.872340 (-5577 3900);
PAINT GREEN (-5577 3900);
DISPLAY INVISIBLE (-5577 3900);
FORCEADD TAP..6
(-5575 3950);
FORCEPROP 3 LASTPIN (-5525 3950) SIG_NAME M_E_DQ<49>
J 0
(-5515 3960);
DISPLAY 0.659574 (-5515 3960);
PAINT MONO (-5515 3960);
DISPLAY INVISIBLE (-5515 3960);
FORCEPROP 1 LASTPIN (-5525 3950) BN 49
J 0
(-5577 3958);
DISPLAY 0.617021 (-5577 3958);
PAINT PINK (-5577 3958);
FORCEPROP 2 LAST CDS_LIB mstr_standard
J 0
(-5575 3950);
PAINT MONO (-5575 3950);
DISPLAY INVISIBLE (-5575 3950);
FORCEPROP 1 LAST BODY_TYPE PLUMBING
J 0
(-5575 3900);
DISPLAY 1.595745 (-5575 3900);
PAINT GREEN (-5575 3900);
DISPLAY INVISIBLE (-5575 3900);
FORCEPROP 1 LAST HDL_TAP TRUE
J 0
(-5250 3825);
DISPLAY 1.595745 (-5250 3825);
PAINT GREEN (-5250 3825);
DISPLAY INVISIBLE (-5250 3825);
FORCEPROP 1 LAST PATH I71
J 0
(-5577 3950);
DISPLAY 0.872340 (-5577 3950);
PAINT GREEN (-5577 3950);
DISPLAY INVISIBLE (-5577 3950);
FORCEADD TAP..6
(-5575 4000);
FORCEPROP 3 LASTPIN (-5525 4000) SIG_NAME M_E_DQ<50>
J 0
(-5515 4010);
DISPLAY 0.659574 (-5515 4010);
PAINT MONO (-5515 4010);
DISPLAY INVISIBLE (-5515 4010);
FORCEPROP 1 LASTPIN (-5525 4000) BN 50
J 0
(-5577 4008);
DISPLAY 0.617021 (-5577 4008);
PAINT PINK (-5577 4008);
FORCEPROP 2 LAST CDS_LIB mstr_standard
J 0
(-5575 4000);
PAINT MONO (-5575 4000);
DISPLAY INVISIBLE (-5575 4000);
FORCEPROP 1 LAST BODY_TYPE PLUMBING
J 0
(-5575 3950);
DISPLAY 1.595745 (-5575 3950);
PAINT GREEN (-5575 3950);
DISPLAY INVISIBLE (-5575 3950);
FORCEPROP 1 LAST HDL_TAP TRUE
J 0
(-5250 3875);
DISPLAY 1.595745 (-5250 3875);
PAINT GREEN (-5250 3875);
DISPLAY INVISIBLE (-5250 3875);
FORCEPROP 1 LAST PATH I72
J 0
(-5577 4000);
DISPLAY 0.872340 (-5577 4000);
PAINT GREEN (-5577 4000);
DISPLAY INVISIBLE (-5577 4000);
FORCEADD OFFPAGE..6
(-6425 4775);
FORCEPROP 2 LAST $XR0 51 
J 0
(-6674 4775);
DISPLAY 0.638298 (-6674 4775);
PAINT MONO (-6674 4775);
FORCEPROP 2 LAST $XR1 52 
J 0
(-6764 4775);
DISPLAY 0.638298 (-6764 4775);
PAINT MONO (-6764 4775);
FORCEPROP 2 LAST CDS_LIB mstr_standard
J 0
(-6425 4775);
PAINT MONO (-6425 4775);
DISPLAY INVISIBLE (-6425 4775);
FORCEPROP 1 LAST OFFPAGE TRUE
J 0
(-6100 4650);
DISPLAY 1.170213 (-6100 4650);
PAINT GREEN (-6100 4650);
DISPLAY INVISIBLE (-6100 4650);
FORCEPROP 1 LAST COMMENT_BODY TRUE
J 0
(-6325 4700);
DISPLAY 1.170213 (-6325 4700);
PAINT GREEN (-6325 4700);
DISPLAY INVISIBLE (-6325 4700);
FORCEPROP 2 LAST PATH I73
J 0
(-6375 4850);
DISPLAY 1.021277 (-6375 4850);
PAINT ORANGE (-6375 4850);
DISPLAY INVISIBLE (-6375 4850);
FORCEADD TAP..6
(-5575 4050);
FORCEPROP 3 LASTPIN (-5525 4050) SIG_NAME M_E_DQ<51>
J 0
(-5515 4060);
DISPLAY 0.659574 (-5515 4060);
PAINT MONO (-5515 4060);
DISPLAY INVISIBLE (-5515 4060);
FORCEPROP 1 LASTPIN (-5525 4050) BN 51
J 0
(-5577 4058);
DISPLAY 0.617021 (-5577 4058);
PAINT PINK (-5577 4058);
FORCEPROP 2 LAST CDS_LIB mstr_standard
J 0
(-5575 4050);
PAINT MONO (-5575 4050);
DISPLAY INVISIBLE (-5575 4050);
FORCEPROP 1 LAST BODY_TYPE PLUMBING
J 0
(-5575 4000);
DISPLAY 1.595745 (-5575 4000);
PAINT GREEN (-5575 4000);
DISPLAY INVISIBLE (-5575 4000);
FORCEPROP 1 LAST HDL_TAP TRUE
J 0
(-5250 3925);
DISPLAY 1.595745 (-5250 3925);
PAINT GREEN (-5250 3925);
DISPLAY INVISIBLE (-5250 3925);
FORCEPROP 1 LAST PATH I74
J 0
(-5577 4050);
DISPLAY 0.872340 (-5577 4050);
PAINT GREEN (-5577 4050);
DISPLAY INVISIBLE (-5577 4050);
FORCEADD TAP..6
(-5575 4100);
FORCEPROP 3 LASTPIN (-5525 4100) SIG_NAME M_E_DQ<52>
J 0
(-5515 4110);
DISPLAY 0.659574 (-5515 4110);
PAINT MONO (-5515 4110);
DISPLAY INVISIBLE (-5515 4110);
FORCEPROP 1 LASTPIN (-5525 4100) BN 52
J 0
(-5577 4108);
DISPLAY 0.617021 (-5577 4108);
PAINT PINK (-5577 4108);
FORCEPROP 2 LAST CDS_LIB mstr_standard
J 0
(-5575 4100);
PAINT MONO (-5575 4100);
DISPLAY INVISIBLE (-5575 4100);
FORCEPROP 1 LAST BODY_TYPE PLUMBING
J 0
(-5575 4050);
DISPLAY 1.595745 (-5575 4050);
PAINT GREEN (-5575 4050);
DISPLAY INVISIBLE (-5575 4050);
FORCEPROP 1 LAST HDL_TAP TRUE
J 0
(-5250 3975);
DISPLAY 1.595745 (-5250 3975);
PAINT GREEN (-5250 3975);
DISPLAY INVISIBLE (-5250 3975);
FORCEPROP 1 LAST PATH I75
J 0
(-5577 4100);
DISPLAY 0.872340 (-5577 4100);
PAINT GREEN (-5577 4100);
DISPLAY INVISIBLE (-5577 4100);
FORCEADD TAP..6
(-5575 4150);
FORCEPROP 3 LASTPIN (-5525 4150) SIG_NAME M_E_DQ<53>
J 0
(-5515 4160);
DISPLAY 0.659574 (-5515 4160);
PAINT MONO (-5515 4160);
DISPLAY INVISIBLE (-5515 4160);
FORCEPROP 1 LASTPIN (-5525 4150) BN 53
J 0
(-5577 4158);
DISPLAY 0.617021 (-5577 4158);
PAINT PINK (-5577 4158);
FORCEPROP 2 LAST CDS_LIB mstr_standard
J 0
(-5575 4150);
PAINT MONO (-5575 4150);
DISPLAY INVISIBLE (-5575 4150);
FORCEPROP 1 LAST BODY_TYPE PLUMBING
J 0
(-5575 4100);
DISPLAY 1.595745 (-5575 4100);
PAINT GREEN (-5575 4100);
DISPLAY INVISIBLE (-5575 4100);
FORCEPROP 1 LAST HDL_TAP TRUE
J 0
(-5250 4025);
DISPLAY 1.595745 (-5250 4025);
PAINT GREEN (-5250 4025);
DISPLAY INVISIBLE (-5250 4025);
FORCEPROP 1 LAST PATH I76
J 0
(-5577 4150);
DISPLAY 0.872340 (-5577 4150);
PAINT GREEN (-5577 4150);
DISPLAY INVISIBLE (-5577 4150);
FORCEADD TAP..6
(-5575 4200);
FORCEPROP 3 LASTPIN (-5525 4200) SIG_NAME M_E_DQ<54>
J 0
(-5515 4210);
DISPLAY 0.659574 (-5515 4210);
PAINT MONO (-5515 4210);
DISPLAY INVISIBLE (-5515 4210);
FORCEPROP 1 LASTPIN (-5525 4200) BN 54
J 0
(-5577 4208);
DISPLAY 0.617021 (-5577 4208);
PAINT PINK (-5577 4208);
FORCEPROP 2 LAST CDS_LIB mstr_standard
J 0
(-5575 4200);
PAINT MONO (-5575 4200);
DISPLAY INVISIBLE (-5575 4200);
FORCEPROP 1 LAST BODY_TYPE PLUMBING
J 0
(-5575 4150);
DISPLAY 1.595745 (-5575 4150);
PAINT GREEN (-5575 4150);
DISPLAY INVISIBLE (-5575 4150);
FORCEPROP 1 LAST HDL_TAP TRUE
J 0
(-5250 4075);
DISPLAY 1.595745 (-5250 4075);
PAINT GREEN (-5250 4075);
DISPLAY INVISIBLE (-5250 4075);
FORCEPROP 1 LAST PATH I77
J 0
(-5577 4200);
DISPLAY 0.872340 (-5577 4200);
PAINT GREEN (-5577 4200);
DISPLAY INVISIBLE (-5577 4200);
FORCEADD TAP..6
(-5575 4250);
FORCEPROP 3 LASTPIN (-5525 4250) SIG_NAME M_E_DQ<55>
J 0
(-5515 4260);
DISPLAY 0.659574 (-5515 4260);
PAINT MONO (-5515 4260);
DISPLAY INVISIBLE (-5515 4260);
FORCEPROP 1 LASTPIN (-5525 4250) BN 55
J 0
(-5577 4258);
DISPLAY 0.617021 (-5577 4258);
PAINT PINK (-5577 4258);
FORCEPROP 2 LAST CDS_LIB mstr_standard
J 0
(-5575 4250);
PAINT MONO (-5575 4250);
DISPLAY INVISIBLE (-5575 4250);
FORCEPROP 1 LAST BODY_TYPE PLUMBING
J 0
(-5575 4200);
DISPLAY 1.595745 (-5575 4200);
PAINT GREEN (-5575 4200);
DISPLAY INVISIBLE (-5575 4200);
FORCEPROP 1 LAST HDL_TAP TRUE
J 0
(-5250 4125);
DISPLAY 1.595745 (-5250 4125);
PAINT GREEN (-5250 4125);
DISPLAY INVISIBLE (-5250 4125);
FORCEPROP 1 LAST PATH I78
J 0
(-5577 4250);
DISPLAY 0.872340 (-5577 4250);
PAINT GREEN (-5577 4250);
DISPLAY INVISIBLE (-5577 4250);
FORCEADD TAP..6
(-5575 4300);
FORCEPROP 3 LASTPIN (-5525 4300) SIG_NAME M_E_DQ<56>
J 0
(-5515 4310);
DISPLAY 0.659574 (-5515 4310);
PAINT MONO (-5515 4310);
DISPLAY INVISIBLE (-5515 4310);
FORCEPROP 1 LASTPIN (-5525 4300) BN 56
J 0
(-5577 4308);
DISPLAY 0.617021 (-5577 4308);
PAINT PINK (-5577 4308);
FORCEPROP 2 LAST CDS_LIB mstr_standard
J 0
(-5575 4300);
PAINT MONO (-5575 4300);
DISPLAY INVISIBLE (-5575 4300);
FORCEPROP 1 LAST BODY_TYPE PLUMBING
J 0
(-5575 4250);
DISPLAY 1.595745 (-5575 4250);
PAINT GREEN (-5575 4250);
DISPLAY INVISIBLE (-5575 4250);
FORCEPROP 1 LAST HDL_TAP TRUE
J 0
(-5250 4175);
DISPLAY 1.595745 (-5250 4175);
PAINT GREEN (-5250 4175);
DISPLAY INVISIBLE (-5250 4175);
FORCEPROP 1 LAST PATH I79
J 0
(-5577 4300);
DISPLAY 0.872340 (-5577 4300);
PAINT GREEN (-5577 4300);
DISPLAY INVISIBLE (-5577 4300);
FORCEADD TAP..6
(-5575 700);
FORCEPROP 3 LASTPIN (-5525 700) SIG_NAME M_E_CLK_DN<2>
J 0
(-5515 710);
DISPLAY 0.659574 (-5515 710);
PAINT MONO (-5515 710);
DISPLAY INVISIBLE (-5515 710);
FORCEPROP 1 LASTPIN (-5525 700) BN 2
J 0
(-5577 708);
DISPLAY 0.617021 (-5577 708);
PAINT PINK (-5577 708);
FORCEPROP 2 LAST CDS_LIB mstr_standard
J 0
(-5575 700);
PAINT MONO (-5575 700);
DISPLAY INVISIBLE (-5575 700);
FORCEPROP 1 LAST BODY_TYPE PLUMBING
J 0
(-5575 650);
DISPLAY 1.595745 (-5575 650);
PAINT GREEN (-5575 650);
DISPLAY INVISIBLE (-5575 650);
FORCEPROP 1 LAST HDL_TAP TRUE
J 0
(-5250 575);
DISPLAY 1.595745 (-5250 575);
PAINT GREEN (-5250 575);
DISPLAY INVISIBLE (-5250 575);
FORCEPROP 1 LAST PATH I8
J 0
(-5577 700);
DISPLAY 0.872340 (-5577 700);
PAINT GREEN (-5577 700);
DISPLAY INVISIBLE (-5577 700);
FORCEADD TAP..6
(-5575 4350);
FORCEPROP 3 LASTPIN (-5525 4350) SIG_NAME M_E_DQ<57>
J 0
(-5515 4360);
DISPLAY 0.659574 (-5515 4360);
PAINT MONO (-5515 4360);
DISPLAY INVISIBLE (-5515 4360);
FORCEPROP 1 LASTPIN (-5525 4350) BN 57
J 0
(-5577 4358);
DISPLAY 0.617021 (-5577 4358);
PAINT PINK (-5577 4358);
FORCEPROP 2 LAST CDS_LIB mstr_standard
J 0
(-5575 4350);
PAINT MONO (-5575 4350);
DISPLAY INVISIBLE (-5575 4350);
FORCEPROP 1 LAST BODY_TYPE PLUMBING
J 0
(-5575 4300);
DISPLAY 1.595745 (-5575 4300);
PAINT GREEN (-5575 4300);
DISPLAY INVISIBLE (-5575 4300);
FORCEPROP 1 LAST HDL_TAP TRUE
J 0
(-5250 4225);
DISPLAY 1.595745 (-5250 4225);
PAINT GREEN (-5250 4225);
DISPLAY INVISIBLE (-5250 4225);
FORCEPROP 1 LAST PATH I80
J 0
(-5577 4350);
DISPLAY 0.872340 (-5577 4350);
PAINT GREEN (-5577 4350);
DISPLAY INVISIBLE (-5577 4350);
FORCEADD TAP..6
(-5575 4400);
FORCEPROP 3 LASTPIN (-5525 4400) SIG_NAME M_E_DQ<58>
J 0
(-5515 4410);
DISPLAY 0.659574 (-5515 4410);
PAINT MONO (-5515 4410);
DISPLAY INVISIBLE (-5515 4410);
FORCEPROP 1 LASTPIN (-5525 4400) BN 58
J 0
(-5577 4408);
DISPLAY 0.617021 (-5577 4408);
PAINT PINK (-5577 4408);
FORCEPROP 2 LAST CDS_LIB mstr_standard
J 0
(-5575 4400);
PAINT MONO (-5575 4400);
DISPLAY INVISIBLE (-5575 4400);
FORCEPROP 1 LAST BODY_TYPE PLUMBING
J 0
(-5575 4350);
DISPLAY 1.595745 (-5575 4350);
PAINT GREEN (-5575 4350);
DISPLAY INVISIBLE (-5575 4350);
FORCEPROP 1 LAST HDL_TAP TRUE
J 0
(-5250 4275);
DISPLAY 1.595745 (-5250 4275);
PAINT GREEN (-5250 4275);
DISPLAY INVISIBLE (-5250 4275);
FORCEPROP 1 LAST PATH I81
J 0
(-5577 4400);
DISPLAY 0.872340 (-5577 4400);
PAINT GREEN (-5577 4400);
DISPLAY INVISIBLE (-5577 4400);
FORCEADD TAP..6
(-5575 4450);
FORCEPROP 3 LASTPIN (-5525 4450) SIG_NAME M_E_DQ<59>
J 0
(-5515 4460);
DISPLAY 0.659574 (-5515 4460);
PAINT MONO (-5515 4460);
DISPLAY INVISIBLE (-5515 4460);
FORCEPROP 1 LASTPIN (-5525 4450) BN 59
J 0
(-5577 4458);
DISPLAY 0.617021 (-5577 4458);
PAINT PINK (-5577 4458);
FORCEPROP 2 LAST CDS_LIB mstr_standard
J 0
(-5575 4450);
PAINT MONO (-5575 4450);
DISPLAY INVISIBLE (-5575 4450);
FORCEPROP 1 LAST BODY_TYPE PLUMBING
J 0
(-5575 4400);
DISPLAY 1.595745 (-5575 4400);
PAINT GREEN (-5575 4400);
DISPLAY INVISIBLE (-5575 4400);
FORCEPROP 1 LAST HDL_TAP TRUE
J 0
(-5250 4325);
DISPLAY 1.595745 (-5250 4325);
PAINT GREEN (-5250 4325);
DISPLAY INVISIBLE (-5250 4325);
FORCEPROP 1 LAST PATH I82
J 0
(-5577 4450);
DISPLAY 0.872340 (-5577 4450);
PAINT GREEN (-5577 4450);
DISPLAY INVISIBLE (-5577 4450);
FORCEADD TAP..6
(-5575 4500);
FORCEPROP 3 LASTPIN (-5525 4500) SIG_NAME M_E_DQ<60>
J 0
(-5515 4510);
DISPLAY 0.659574 (-5515 4510);
PAINT MONO (-5515 4510);
DISPLAY INVISIBLE (-5515 4510);
FORCEPROP 1 LASTPIN (-5525 4500) BN 60
J 0
(-5577 4508);
DISPLAY 0.617021 (-5577 4508);
PAINT PINK (-5577 4508);
FORCEPROP 2 LAST CDS_LIB mstr_standard
J 0
(-5575 4500);
PAINT MONO (-5575 4500);
DISPLAY INVISIBLE (-5575 4500);
FORCEPROP 1 LAST BODY_TYPE PLUMBING
J 0
(-5575 4450);
DISPLAY 1.595745 (-5575 4450);
PAINT GREEN (-5575 4450);
DISPLAY INVISIBLE (-5575 4450);
FORCEPROP 1 LAST HDL_TAP TRUE
J 0
(-5250 4375);
DISPLAY 1.595745 (-5250 4375);
PAINT GREEN (-5250 4375);
DISPLAY INVISIBLE (-5250 4375);
FORCEPROP 1 LAST PATH I83
J 0
(-5577 4500);
DISPLAY 0.872340 (-5577 4500);
PAINT GREEN (-5577 4500);
DISPLAY INVISIBLE (-5577 4500);
FORCEADD TAP..6
(-5575 4550);
FORCEPROP 3 LASTPIN (-5525 4550) SIG_NAME M_E_DQ<61>
J 0
(-5515 4560);
DISPLAY 0.659574 (-5515 4560);
PAINT MONO (-5515 4560);
DISPLAY INVISIBLE (-5515 4560);
FORCEPROP 1 LASTPIN (-5525 4550) BN 61
J 0
(-5577 4558);
DISPLAY 0.617021 (-5577 4558);
PAINT PINK (-5577 4558);
FORCEPROP 2 LAST CDS_LIB mstr_standard
J 0
(-5575 4550);
PAINT MONO (-5575 4550);
DISPLAY INVISIBLE (-5575 4550);
FORCEPROP 1 LAST BODY_TYPE PLUMBING
J 0
(-5575 4500);
DISPLAY 1.595745 (-5575 4500);
PAINT GREEN (-5575 4500);
DISPLAY INVISIBLE (-5575 4500);
FORCEPROP 1 LAST HDL_TAP TRUE
J 0
(-5250 4425);
DISPLAY 1.595745 (-5250 4425);
PAINT GREEN (-5250 4425);
DISPLAY INVISIBLE (-5250 4425);
FORCEPROP 1 LAST PATH I84
J 0
(-5577 4550);
DISPLAY 0.872340 (-5577 4550);
PAINT GREEN (-5577 4550);
DISPLAY INVISIBLE (-5577 4550);
FORCEADD TAP..6
(-5575 4600);
FORCEPROP 3 LASTPIN (-5525 4600) SIG_NAME M_E_DQ<62>
J 0
(-5515 4610);
DISPLAY 0.659574 (-5515 4610);
PAINT MONO (-5515 4610);
DISPLAY INVISIBLE (-5515 4610);
FORCEPROP 1 LASTPIN (-5525 4600) BN 62
J 0
(-5577 4608);
DISPLAY 0.617021 (-5577 4608);
PAINT PINK (-5577 4608);
FORCEPROP 2 LAST CDS_LIB mstr_standard
J 0
(-5575 4600);
PAINT MONO (-5575 4600);
DISPLAY INVISIBLE (-5575 4600);
FORCEPROP 1 LAST BODY_TYPE PLUMBING
J 0
(-5575 4550);
DISPLAY 1.595745 (-5575 4550);
PAINT GREEN (-5575 4550);
DISPLAY INVISIBLE (-5575 4550);
FORCEPROP 1 LAST HDL_TAP TRUE
J 0
(-5250 4475);
DISPLAY 1.595745 (-5250 4475);
PAINT GREEN (-5250 4475);
DISPLAY INVISIBLE (-5250 4475);
FORCEPROP 1 LAST PATH I85
J 0
(-5577 4600);
DISPLAY 0.872340 (-5577 4600);
PAINT GREEN (-5577 4600);
DISPLAY INVISIBLE (-5577 4600);
FORCEADD TAP..6
(-5575 4650);
FORCEPROP 3 LASTPIN (-5525 4650) SIG_NAME M_E_DQ<63>
J 0
(-5515 4660);
DISPLAY 0.659574 (-5515 4660);
PAINT MONO (-5515 4660);
DISPLAY INVISIBLE (-5515 4660);
FORCEPROP 1 LASTPIN (-5525 4650) BN 63
J 0
(-5577 4658);
DISPLAY 0.617021 (-5577 4658);
PAINT PINK (-5577 4658);
FORCEPROP 2 LAST CDS_LIB mstr_standard
J 0
(-5575 4650);
PAINT MONO (-5575 4650);
DISPLAY INVISIBLE (-5575 4650);
FORCEPROP 1 LAST BODY_TYPE PLUMBING
J 0
(-5575 4600);
DISPLAY 1.595745 (-5575 4600);
PAINT GREEN (-5575 4600);
DISPLAY INVISIBLE (-5575 4600);
FORCEPROP 1 LAST HDL_TAP TRUE
J 0
(-5250 4525);
DISPLAY 1.595745 (-5250 4525);
PAINT GREEN (-5250 4525);
DISPLAY INVISIBLE (-5250 4525);
FORCEPROP 1 LAST PATH I86
J 0
(-5577 4650);
DISPLAY 0.872340 (-5577 4650);
PAINT GREEN (-5577 4650);
DISPLAY INVISIBLE (-5577 4650);
FORCEADD TAP..6
R 2
(-2850 800);
FORCEPROP 3 LASTPIN (-2900 800) SIG_NAME M_E_BG<0>
J 0
(-2890 810);
DISPLAY 0.659574 (-2890 810);
PAINT MONO (-2890 810);
DISPLAY INVISIBLE (-2890 810);
FORCEPROP 1 LASTPIN (-2900 800) BN 0
J 2
(-2848 808);
DISPLAY 0.617021 (-2848 808);
PAINT PINK (-2848 808);
FORCEPROP 2 LAST CDS_LIB mstr_standard
J 0
(-2850 800);
PAINT MONO (-2850 800);
DISPLAY INVISIBLE (-2850 800);
FORCEPROP 1 LAST BODY_TYPE PLUMBING
J 2
(-2850 750);
DISPLAY 1.595745 (-2850 750);
PAINT GREEN (-2850 750);
DISPLAY INVISIBLE (-2850 750);
FORCEPROP 1 LAST HDL_TAP TRUE
J 2
(-3175 675);
DISPLAY 1.595745 (-3175 675);
PAINT GREEN (-3175 675);
DISPLAY INVISIBLE (-3175 675);
FORCEPROP 1 LAST PATH I87
J 2
(-2848 800);
DISPLAY 0.872340 (-2848 800);
PAINT GREEN (-2848 800);
DISPLAY INVISIBLE (-2848 800);
FORCEADD TAP..6
R 2
(-2850 750);
FORCEPROP 3 LASTPIN (-2900 750) SIG_NAME M_E_BA<1>
J 0
(-2890 760);
DISPLAY 0.659574 (-2890 760);
PAINT MONO (-2890 760);
DISPLAY INVISIBLE (-2890 760);
FORCEPROP 1 LASTPIN (-2900 750) BN 1
J 2
(-2848 758);
DISPLAY 0.617021 (-2848 758);
PAINT PINK (-2848 758);
FORCEPROP 2 LAST CDS_LIB mstr_standard
J 0
(-2850 750);
PAINT MONO (-2850 750);
DISPLAY INVISIBLE (-2850 750);
FORCEPROP 1 LAST BODY_TYPE PLUMBING
J 2
(-2850 700);
DISPLAY 1.595745 (-2850 700);
PAINT GREEN (-2850 700);
DISPLAY INVISIBLE (-2850 700);
FORCEPROP 1 LAST HDL_TAP TRUE
J 2
(-3175 625);
DISPLAY 1.595745 (-3175 625);
PAINT GREEN (-3175 625);
DISPLAY INVISIBLE (-3175 625);
FORCEPROP 1 LAST PATH I88
J 2
(-2848 750);
DISPLAY 0.872340 (-2848 750);
PAINT GREEN (-2848 750);
DISPLAY INVISIBLE (-2848 750);
FORCEADD TAP..6
R 2
(-2850 700);
FORCEPROP 3 LASTPIN (-2900 700) SIG_NAME M_E_BA<0>
J 0
(-2890 710);
DISPLAY 0.659574 (-2890 710);
PAINT MONO (-2890 710);
DISPLAY INVISIBLE (-2890 710);
FORCEPROP 1 LASTPIN (-2900 700) BN 0
J 2
(-2848 708);
DISPLAY 0.617021 (-2848 708);
PAINT PINK (-2848 708);
FORCEPROP 2 LAST CDS_LIB mstr_standard
J 0
(-2850 700);
PAINT MONO (-2850 700);
DISPLAY INVISIBLE (-2850 700);
FORCEPROP 1 LAST BODY_TYPE PLUMBING
J 2
(-2850 650);
DISPLAY 1.595745 (-2850 650);
PAINT GREEN (-2850 650);
DISPLAY INVISIBLE (-2850 650);
FORCEPROP 1 LAST HDL_TAP TRUE
J 2
(-3175 575);
DISPLAY 1.595745 (-3175 575);
PAINT GREEN (-3175 575);
DISPLAY INVISIBLE (-3175 575);
FORCEPROP 1 LAST PATH I89
J 2
(-2848 700);
DISPLAY 0.872340 (-2848 700);
PAINT GREEN (-2848 700);
DISPLAY INVISIBLE (-2848 700);
FORCEADD TAP..6
(-5575 800);
FORCEPROP 3 LASTPIN (-5525 800) SIG_NAME M_E_CLK_DP<0>
J 0
(-5515 810);
DISPLAY 0.659574 (-5515 810);
PAINT MONO (-5515 810);
DISPLAY INVISIBLE (-5515 810);
FORCEPROP 1 LASTPIN (-5525 800) BN 0
J 0
(-5577 808);
DISPLAY 0.617021 (-5577 808);
PAINT PINK (-5577 808);
FORCEPROP 2 LAST CDS_LIB mstr_standard
J 0
(-5575 800);
PAINT MONO (-5575 800);
DISPLAY INVISIBLE (-5575 800);
FORCEPROP 1 LAST BODY_TYPE PLUMBING
J 0
(-5575 750);
DISPLAY 1.595745 (-5575 750);
PAINT GREEN (-5575 750);
DISPLAY INVISIBLE (-5575 750);
FORCEPROP 1 LAST HDL_TAP TRUE
J 0
(-5250 675);
DISPLAY 1.595745 (-5250 675);
PAINT GREEN (-5250 675);
DISPLAY INVISIBLE (-5250 675);
FORCEPROP 1 LAST PATH I9
J 0
(-5577 800);
DISPLAY 0.872340 (-5577 800);
PAINT GREEN (-5577 800);
DISPLAY INVISIBLE (-5577 800);
FORCEADD TAP..6
R 2
(-2850 850);
FORCEPROP 3 LASTPIN (-2900 850) SIG_NAME M_E_BG<1>
J 0
(-2890 860);
DISPLAY 0.659574 (-2890 860);
PAINT MONO (-2890 860);
DISPLAY INVISIBLE (-2890 860);
FORCEPROP 1 LASTPIN (-2900 850) BN 1
J 2
(-2848 858);
DISPLAY 0.617021 (-2848 858);
PAINT PINK (-2848 858);
FORCEPROP 2 LAST CDS_LIB mstr_standard
J 0
(-2850 850);
PAINT MONO (-2850 850);
DISPLAY INVISIBLE (-2850 850);
FORCEPROP 1 LAST BODY_TYPE PLUMBING
J 2
(-2850 800);
DISPLAY 1.595745 (-2850 800);
PAINT GREEN (-2850 800);
DISPLAY INVISIBLE (-2850 800);
FORCEPROP 1 LAST HDL_TAP TRUE
J 2
(-3175 725);
DISPLAY 1.595745 (-3175 725);
PAINT GREEN (-3175 725);
DISPLAY INVISIBLE (-3175 725);
FORCEPROP 1 LAST PATH I90
J 2
(-2848 850);
DISPLAY 0.872340 (-2848 850);
PAINT GREEN (-2848 850);
DISPLAY INVISIBLE (-2848 850);
FORCEADD TAP..6
R 2
(-2850 1000);
FORCEPROP 3 LASTPIN (-2900 1000) SIG_NAME M_E_CS_N<1>
J 0
(-2890 1010);
DISPLAY 0.659574 (-2890 1010);
PAINT MONO (-2890 1010);
DISPLAY INVISIBLE (-2890 1010);
FORCEPROP 1 LASTPIN (-2900 1000) BN 1
J 2
(-2848 1008);
DISPLAY 0.617021 (-2848 1008);
PAINT PINK (-2848 1008);
FORCEPROP 2 LAST CDS_LIB mstr_standard
J 0
(-2850 1000);
PAINT MONO (-2850 1000);
DISPLAY INVISIBLE (-2850 1000);
FORCEPROP 1 LAST BODY_TYPE PLUMBING
J 2
(-2850 950);
DISPLAY 1.595745 (-2850 950);
PAINT GREEN (-2850 950);
DISPLAY INVISIBLE (-2850 950);
FORCEPROP 1 LAST HDL_TAP TRUE
J 2
(-3175 875);
DISPLAY 1.595745 (-3175 875);
PAINT GREEN (-3175 875);
DISPLAY INVISIBLE (-3175 875);
FORCEPROP 1 LAST PATH I91
J 2
(-2848 1000);
DISPLAY 0.872340 (-2848 1000);
PAINT GREEN (-2848 1000);
DISPLAY INVISIBLE (-2848 1000);
FORCEADD TAP..6
R 2
(-2850 950);
FORCEPROP 3 LASTPIN (-2900 950) SIG_NAME M_E_CS_N<0>
J 0
(-2890 960);
DISPLAY 0.659574 (-2890 960);
PAINT MONO (-2890 960);
DISPLAY INVISIBLE (-2890 960);
FORCEPROP 1 LASTPIN (-2900 950) BN 0
J 2
(-2848 958);
DISPLAY 0.617021 (-2848 958);
PAINT PINK (-2848 958);
FORCEPROP 2 LAST CDS_LIB mstr_standard
J 0
(-2850 950);
PAINT MONO (-2850 950);
DISPLAY INVISIBLE (-2850 950);
FORCEPROP 1 LAST BODY_TYPE PLUMBING
J 2
(-2850 900);
DISPLAY 1.595745 (-2850 900);
PAINT GREEN (-2850 900);
DISPLAY INVISIBLE (-2850 900);
FORCEPROP 1 LAST HDL_TAP TRUE
J 2
(-3175 825);
DISPLAY 1.595745 (-3175 825);
PAINT GREEN (-3175 825);
DISPLAY INVISIBLE (-3175 825);
FORCEPROP 1 LAST PATH I92
J 2
(-2848 950);
DISPLAY 0.872340 (-2848 950);
PAINT GREEN (-2848 950);
DISPLAY INVISIBLE (-2848 950);
FORCEADD TAP..6
R 2
(-2850 1050);
FORCEPROP 3 LASTPIN (-2900 1050) SIG_NAME M_E_CS_N<2>
J 0
(-2890 1060);
DISPLAY 0.659574 (-2890 1060);
PAINT MONO (-2890 1060);
DISPLAY INVISIBLE (-2890 1060);
FORCEPROP 1 LASTPIN (-2900 1050) BN 2
J 2
(-2848 1058);
DISPLAY 0.617021 (-2848 1058);
PAINT PINK (-2848 1058);
FORCEPROP 2 LAST CDS_LIB mstr_standard
J 0
(-2850 1050);
PAINT MONO (-2850 1050);
DISPLAY INVISIBLE (-2850 1050);
FORCEPROP 1 LAST BODY_TYPE PLUMBING
J 2
(-2850 1000);
DISPLAY 1.595745 (-2850 1000);
PAINT GREEN (-2850 1000);
DISPLAY INVISIBLE (-2850 1000);
FORCEPROP 1 LAST HDL_TAP TRUE
J 2
(-3175 925);
DISPLAY 1.595745 (-3175 925);
PAINT GREEN (-3175 925);
DISPLAY INVISIBLE (-3175 925);
FORCEPROP 1 LAST PATH I93
J 2
(-2848 1050);
DISPLAY 0.872340 (-2848 1050);
PAINT GREEN (-2848 1050);
DISPLAY INVISIBLE (-2848 1050);
FORCEADD TAP..6
R 2
(-2850 1200);
FORCEPROP 3 LASTPIN (-2900 1200) SIG_NAME M_E_CS_N<5>
J 0
(-2890 1210);
DISPLAY 0.659574 (-2890 1210);
PAINT MONO (-2890 1210);
DISPLAY INVISIBLE (-2890 1210);
FORCEPROP 1 LASTPIN (-2900 1200) BN 5
J 2
(-2848 1208);
DISPLAY 0.617021 (-2848 1208);
PAINT PINK (-2848 1208);
FORCEPROP 2 LAST CDS_LIB mstr_standard
J 0
(-2850 1200);
PAINT MONO (-2850 1200);
DISPLAY INVISIBLE (-2850 1200);
FORCEPROP 1 LAST BODY_TYPE PLUMBING
J 2
(-2850 1150);
DISPLAY 1.595745 (-2850 1150);
PAINT GREEN (-2850 1150);
DISPLAY INVISIBLE (-2850 1150);
FORCEPROP 1 LAST HDL_TAP TRUE
J 2
(-3175 1075);
DISPLAY 1.595745 (-3175 1075);
PAINT GREEN (-3175 1075);
DISPLAY INVISIBLE (-3175 1075);
FORCEPROP 1 LAST PATH I94
J 2
(-2848 1200);
DISPLAY 0.872340 (-2848 1200);
PAINT GREEN (-2848 1200);
DISPLAY INVISIBLE (-2848 1200);
FORCEADD TAP..6
R 2
(-2850 1100);
FORCEPROP 3 LASTPIN (-2900 1100) SIG_NAME M_E_CS_N<3>
J 0
(-2890 1110);
DISPLAY 0.659574 (-2890 1110);
PAINT MONO (-2890 1110);
DISPLAY INVISIBLE (-2890 1110);
FORCEPROP 1 LASTPIN (-2900 1100) BN 3
J 2
(-2848 1108);
DISPLAY 0.617021 (-2848 1108);
PAINT PINK (-2848 1108);
FORCEPROP 2 LAST CDS_LIB mstr_standard
J 0
(-2850 1100);
PAINT MONO (-2850 1100);
DISPLAY INVISIBLE (-2850 1100);
FORCEPROP 1 LAST BODY_TYPE PLUMBING
J 2
(-2850 1050);
DISPLAY 1.595745 (-2850 1050);
PAINT GREEN (-2850 1050);
DISPLAY INVISIBLE (-2850 1050);
FORCEPROP 1 LAST HDL_TAP TRUE
J 2
(-3175 975);
DISPLAY 1.595745 (-3175 975);
PAINT GREEN (-3175 975);
DISPLAY INVISIBLE (-3175 975);
FORCEPROP 1 LAST PATH I95
J 2
(-2848 1100);
DISPLAY 0.872340 (-2848 1100);
PAINT GREEN (-2848 1100);
DISPLAY INVISIBLE (-2848 1100);
FORCEADD TAP..6
R 2
(-2850 1150);
FORCEPROP 3 LASTPIN (-2900 1150) SIG_NAME M_E_CS_N<4>
J 0
(-2890 1160);
DISPLAY 0.659574 (-2890 1160);
PAINT MONO (-2890 1160);
DISPLAY INVISIBLE (-2890 1160);
FORCEPROP 1 LASTPIN (-2900 1150) BN 4
J 2
(-2848 1158);
DISPLAY 0.617021 (-2848 1158);
PAINT PINK (-2848 1158);
FORCEPROP 2 LAST CDS_LIB mstr_standard
J 0
(-2850 1150);
PAINT MONO (-2850 1150);
DISPLAY INVISIBLE (-2850 1150);
FORCEPROP 1 LAST BODY_TYPE PLUMBING
J 2
(-2850 1100);
DISPLAY 1.595745 (-2850 1100);
PAINT GREEN (-2850 1100);
DISPLAY INVISIBLE (-2850 1100);
FORCEPROP 1 LAST HDL_TAP TRUE
J 2
(-3175 1025);
DISPLAY 1.595745 (-3175 1025);
PAINT GREEN (-3175 1025);
DISPLAY INVISIBLE (-3175 1025);
FORCEPROP 1 LAST PATH I96
J 2
(-2848 1150);
DISPLAY 0.872340 (-2848 1150);
PAINT GREEN (-2848 1150);
DISPLAY INVISIBLE (-2848 1150);
FORCEADD TAP..6
R 2
(-2850 1250);
FORCEPROP 3 LASTPIN (-2900 1250) SIG_NAME M_E_CS_N<6>
J 0
(-2890 1260);
DISPLAY 0.659574 (-2890 1260);
PAINT MONO (-2890 1260);
DISPLAY INVISIBLE (-2890 1260);
FORCEPROP 1 LASTPIN (-2900 1250) BN 6
J 2
(-2848 1258);
DISPLAY 0.617021 (-2848 1258);
PAINT PINK (-2848 1258);
FORCEPROP 2 LAST CDS_LIB mstr_standard
J 0
(-2850 1250);
PAINT MONO (-2850 1250);
DISPLAY INVISIBLE (-2850 1250);
FORCEPROP 1 LAST BODY_TYPE PLUMBING
J 2
(-2850 1200);
DISPLAY 1.595745 (-2850 1200);
PAINT GREEN (-2850 1200);
DISPLAY INVISIBLE (-2850 1200);
FORCEPROP 1 LAST HDL_TAP TRUE
J 2
(-3175 1125);
DISPLAY 1.595745 (-3175 1125);
PAINT GREEN (-3175 1125);
DISPLAY INVISIBLE (-3175 1125);
FORCEPROP 1 LAST PATH I97
J 2
(-2848 1250);
DISPLAY 0.872340 (-2848 1250);
PAINT GREEN (-2848 1250);
DISPLAY INVISIBLE (-2848 1250);
FORCEADD TAP..6
R 2
(-2850 1300);
FORCEPROP 3 LASTPIN (-2900 1300) SIG_NAME M_E_CS_N<7>
J 0
(-2890 1310);
DISPLAY 0.659574 (-2890 1310);
PAINT MONO (-2890 1310);
DISPLAY INVISIBLE (-2890 1310);
FORCEPROP 1 LASTPIN (-2900 1300) BN 7
J 2
(-2848 1308);
DISPLAY 0.617021 (-2848 1308);
PAINT PINK (-2848 1308);
FORCEPROP 2 LAST CDS_LIB mstr_standard
J 0
(-2850 1300);
PAINT MONO (-2850 1300);
DISPLAY INVISIBLE (-2850 1300);
FORCEPROP 1 LAST BODY_TYPE PLUMBING
J 2
(-2850 1250);
DISPLAY 1.595745 (-2850 1250);
PAINT GREEN (-2850 1250);
DISPLAY INVISIBLE (-2850 1250);
FORCEPROP 1 LAST HDL_TAP TRUE
J 2
(-3175 1175);
DISPLAY 1.595745 (-3175 1175);
PAINT GREEN (-3175 1175);
DISPLAY INVISIBLE (-3175 1175);
FORCEPROP 1 LAST PATH I98
J 2
(-2848 1300);
DISPLAY 0.872340 (-2848 1300);
PAINT GREEN (-2848 1300);
DISPLAY INVISIBLE (-2848 1300);
FORCEADD TAP..6
R 2
(-2850 1450);
FORCEPROP 3 LASTPIN (-2900 1450) SIG_NAME M_E_ODT<1>
J 0
(-2890 1460);
DISPLAY 0.659574 (-2890 1460);
PAINT MONO (-2890 1460);
DISPLAY INVISIBLE (-2890 1460);
FORCEPROP 1 LASTPIN (-2900 1450) BN 1
J 2
(-2848 1458);
DISPLAY 0.617021 (-2848 1458);
PAINT PINK (-2848 1458);
FORCEPROP 2 LAST CDS_LIB mstr_standard
J 0
(-2850 1450);
PAINT MONO (-2850 1450);
DISPLAY INVISIBLE (-2850 1450);
FORCEPROP 1 LAST BODY_TYPE PLUMBING
J 2
(-2850 1400);
DISPLAY 1.595745 (-2850 1400);
PAINT GREEN (-2850 1400);
DISPLAY INVISIBLE (-2850 1400);
FORCEPROP 1 LAST HDL_TAP TRUE
J 2
(-3175 1325);
DISPLAY 1.595745 (-3175 1325);
PAINT GREEN (-3175 1325);
DISPLAY INVISIBLE (-3175 1325);
FORCEPROP 1 LAST PATH I99
J 2
(-2848 1450);
DISPLAY 0.872340 (-2848 1450);
PAINT GREEN (-2848 1450);
DISPLAY INVISIBLE (-2848 1450);
FORCEADD DESIGN_NOTE..1
(-6500 300);
FORCEPROP 0 LAST L1 CPU SYMBOLS 1-30 ARE PRELIMINARY AND SUBJECT TO CHANGE
J 0
(-6700 175);
DISPLAY 1.021277 (-6700 175);
PAINT ORANGE (-6700 175);
FORCEPROP 2 LAST CDS_LIB mstr_symbols
J 0
(-6500 300);
PAINT ORANGE (-6500 300);
DISPLAY INVISIBLE (-6500 300);
FORCEPROP 1 LAST COMMENT_BODY TRUE
J 0
(-6475 400);
DISPLAY 0.978723 (-6475 400);
PAINT ORANGE (-6475 400);
DISPLAY INVISIBLE (-6475 400);
FORCEADD PRELIM..10
(-4215 2540);
PAINT GRAY (-4215 2540);
FORCEPROP 2 LAST CDS_LIB mstr_misc
J 0
(-4215 2540);
PAINT ORANGE (-4215 2540);
DISPLAY INVISIBLE (-4215 2540);
FORCEPROP 1 LAST COMMENT_BODY TRUE
J 0
(-4215 2540);
PAINT ORANGE (-4215 2540);
DISPLAY INVISIBLE (-4215 2540);
FORCEADD INTEL_CORP_BPAGE..1
(0 0);
FORCEPROP 1 LAST CDS_CON_LAST_MODIFIED Tue Dec 01 11:51:19 2015
J 0
(-1425 325);
DISPLAY 1.340426 (-1425 325);
PAINT GREEN (-1425 325);
DISPLAY INVISIBLE (-1425 325);
FORCEPROP 1 LAST CUSTOM_TXT_CDS <CURRENT_DESIGN_SHEET> OF <TOTAL_DESIGN_SHEETS>
J 0
(-500 25);
PAINT GREEN (-500 25);
FORCEPROP 1 LAST CUSTOM_TXT_CDS <CON_LAST_MODIFIED>
J 0
(-1925 350);
PAINT GREEN (-1925 350);
FORCEPROP 2 LAST CUSTOM_TXT_CDS <XR_PAGE_TITLE>
J 0
(-7890 5250);
DISPLAY 0.638298 (-7890 5250);
PAINT PINK (-7890 5250);
DISPLAY INVISIBLE (-7890 5250);
FORCEPROP 1 LAST SCH_ADDRESS3 Santa Clara, CA 95052-8119
J 0
(-3975 25);
DISPLAY 0.617021 (-3975 25);
PAINT GREEN (-3975 25);
FORCEPROP 1 LAST SCH_ADDRESS2 P.O. BOX 58119
J 0
(-3975 75);
DISPLAY 0.617021 (-3975 75);
PAINT GREEN (-3975 75);
FORCEPROP 1 LAST SCH_ADDRESS1 2200 Mission College Blvd.
J 0
(-3975 125);
DISPLAY 0.617021 (-3975 125);
PAINT GREEN (-3975 125);
FORCEPROP 1 LAST SCH_TITLE SKYLAKE - SKT0 - 7 OF 21
J 0
(-7950 50);
DISPLAY 1.212766 (-7950 50);
PAINT GREEN (-7950 50);
FORCEPROP 1 LAST SCH_NUMBER H4694802
J 0
(-1300 150);
DISPLAY 1.212766 (-1300 150);
PAINT YELLOW (-1300 150);
FORCEPROP 1 LAST SCH_DEPT BESD
J 1
(-4450 100);
DISPLAY 1.212766 (-4450 100);
PAINT YELLOW (-4450 100);
FORCEPROP 1 LAST SCH_REV 2.420
J 0
(-250 150);
DISPLAY 0.978723 (-250 150);
PAINT YELLOW (-250 150);
FORCEPROP 2 LAST PAGE_BORDER TRUE
J 0
(-7890 5250);
DISPLAY 0.851064 (-7890 5250);
PAINT PINK (-7890 5250);
DISPLAY INVISIBLE (-7890 5250);
FORCEPROP 2 LAST CDS_LIB mstr_symbols
J 0
(0 0);
PAINT ORANGE (0 0);
DISPLAY INVISIBLE (0 0);
FORCEPROP 1 LAST COMMENT_BODY TRUE
J 0
(12 12);
DISPLAY 0.638298 (12 12);
PAINT GREEN (12 12);
DISPLAY INVISIBLE (12 12);
FORCEPROP 2 LAST CDS_XR_PAGE_TITLE CR-27 : @BASEBOARD_FAB2_LIB.BASEBOARD_FAB2(SCH_1):PAGE27
J 0
(-7890 5250);
DISPLAY 0.638298 (-7890 5250);
PAINT PINK (-7890 5250);
DISPLAY INVISIBLE (-7890 5250);
WIRE 17 -1 (-2800 4625)(-2800 4675);
WIRE 17 -1 (-2800 4575)(-2800 4625);
WIRE 17 -1 (-2800 4675)(-2800 4725);
WIRE 17 -1 (-2050 4725)(-2800 4725);
FORCEPROP 2 LAST SIG_NAME M_E_DQS_DP<17:0>
J 0
(-2700 4735);
DISPLAY 0.617021 (-2700 4735);
PAINT ORANGE (-2700 4735);
WIRE 17 -1 (-2800 4525)(-2800 4575);
WIRE 17 -1 (-2800 4475)(-2800 4525);
WIRE 17 -1 (-2800 4425)(-2800 4475);
WIRE 17 -1 (-2800 4375)(-2800 4425);
WIRE 17 -1 (-2800 4325)(-2800 4375);
WIRE 17 -1 (-2800 4275)(-2800 4325);
WIRE 17 -1 (-2800 4225)(-2800 4275);
WIRE 17 -1 (-2800 4175)(-2800 4225);
WIRE 17 -1 (-2800 4125)(-2800 4175);
WIRE 17 -1 (-2800 4075)(-2800 4125);
WIRE 17 -1 (-2800 4025)(-2800 4075);
WIRE 17 -1 (-2800 3975)(-2800 4025);
WIRE 17 -1 (-2800 3925)(-2800 3975);
WIRE 17 -1 (-2800 3875)(-2800 3925);
WIRE 17 -1 (-2800 3825)(-2800 3875);
WIRE 17 -1 (-2800 3675)(-2800 3725);
WIRE 17 -1 (-2800 3625)(-2800 3675);
WIRE 17 -1 (-2800 3725)(-2800 3750);
WIRE 17 -1 (-2050 3750)(-2800 3750);
FORCEPROP 2 LAST SIG_NAME M_E_DQS_DN<17:0>
J 0
(-2700 3760);
DISPLAY 0.617021 (-2700 3760);
PAINT ORANGE (-2700 3760);
WIRE 17 -1 (-2800 3575)(-2800 3625);
WIRE 17 -1 (-2800 3525)(-2800 3575);
WIRE 17 -1 (-2800 3475)(-2800 3525);
WIRE 17 -1 (-2800 3425)(-2800 3475);
WIRE 17 -1 (-2800 3375)(-2800 3425);
WIRE 17 -1 (-2800 3325)(-2800 3375);
WIRE 17 -1 (-2800 3275)(-2800 3325);
WIRE 17 -1 (-2800 3225)(-2800 3275);
WIRE 17 -1 (-2800 3175)(-2800 3225);
WIRE 17 -1 (-2800 3125)(-2800 3175);
WIRE 17 -1 (-2800 3075)(-2800 3125);
WIRE 17 -1 (-2800 3025)(-2800 3075);
WIRE 17 -1 (-2800 2975)(-2800 3025);
WIRE 17 -1 (-2800 2925)(-2800 2975);
WIRE 17 -1 (-2800 2875)(-2800 2925);
WIRE 17 -1 (-2800 2725)(-2800 2775);
WIRE 17 -1 (-2800 2675)(-2800 2725);
WIRE 17 -1 (-2800 2775)(-2800 2800);
WIRE 17 -1 (-2050 2800)(-2800 2800);
FORCEPROP 2 LAST SIG_NAME M_E_MA<17:0>
J 0
(-2700 2810);
DISPLAY 0.617021 (-2700 2810);
PAINT ORANGE (-2700 2810);
WIRE 17 -1 (-2800 2625)(-2800 2675);
WIRE 17 -1 (-2800 2575)(-2800 2625);
WIRE 17 -1 (-2800 2525)(-2800 2575);
WIRE 17 -1 (-2800 2475)(-2800 2525);
WIRE 17 -1 (-2800 2425)(-2800 2475);
WIRE 17 -1 (-2800 2375)(-2800 2425);
WIRE 17 -1 (-2800 2325)(-2800 2375);
WIRE 17 -1 (-2800 2275)(-2800 2325);
WIRE 17 -1 (-2800 2225)(-2800 2275);
WIRE 17 -1 (-2800 2175)(-2800 2225);
WIRE 17 -1 (-2800 2125)(-2800 2175);
WIRE 17 -1 (-2800 2075)(-2800 2125);
WIRE 17 -1 (-2800 2025)(-2800 2075);
WIRE 17 -1 (-2800 1975)(-2800 2025);
WIRE 17 -1 (-2800 1925)(-2800 1975);
WIRE 17 -1 (-2800 775)(-2800 800);
WIRE 17 -1 (-2800 725)(-2800 775);
WIRE 17 -1 (-2050 800)(-2800 800);
FORCEPROP 2 LAST SIG_NAME M_E_BA<1:0>
J 0
(-2700 810);
DISPLAY 0.617021 (-2700 810);
PAINT ORANGE (-2700 810);
WIRE 17 -1 (-2800 825)(-2800 875);
WIRE 17 -1 (-2800 875)(-2800 900);
WIRE 17 -1 (-2050 900)(-2800 900);
FORCEPROP 2 LAST SIG_NAME M_E_BG<1:0>
J 0
(-2700 910);
DISPLAY 0.617021 (-2700 910);
PAINT ORANGE (-2700 910);
WIRE 17 -1 (-2800 1775)(-2800 1825);
WIRE 17 -1 (-2800 1725)(-2800 1775);
WIRE 17 -1 (-2800 1825)(-2800 1850);
WIRE 17 -1 (-2050 1850)(-2800 1850);
FORCEPROP 2 LAST SIG_NAME M_E_CKE<3:0>
J 0
(-2700 1860);
DISPLAY 0.617021 (-2700 1860);
PAINT ORANGE (-2700 1860);
WIRE 17 -1 (-2800 1675)(-2800 1725);
WIRE 17 -1 (-2800 1275)(-2800 1325);
WIRE 17 -1 (-2800 1225)(-2800 1275);
WIRE 17 -1 (-2800 1325)(-2800 1350);
WIRE 17 -1 (-2050 1350)(-2800 1350);
FORCEPROP 2 LAST SIG_NAME M_E_CS_N<7:0>
J 0
(-2700 1360);
DISPLAY 0.617021 (-2700 1360);
PAINT ORANGE (-2700 1360);
WIRE 17 -1 (-2800 1175)(-2800 1225);
WIRE 17 -1 (-2800 1125)(-2800 1175);
WIRE 17 -1 (-2800 1075)(-2800 1125);
WIRE 17 -1 (-2800 1025)(-2800 1075);
WIRE 17 -1 (-2800 975)(-2800 1025);
WIRE 17 -1 (-2800 1525)(-2800 1575);
WIRE 17 -1 (-2800 1475)(-2800 1525);
WIRE 17 -1 (-2800 1575)(-2800 1600);
WIRE 17 -1 (-2050 1600)(-2800 1600);
FORCEPROP 2 LAST SIG_NAME M_E_ODT<3:0>
J 0
(-2700 1610);
DISPLAY 0.617021 (-2700 1610);
PAINT ORANGE (-2700 1610);
WIRE 17 -1 (-2800 1425)(-2800 1475);
WIRE 17 -1 (-5625 4625)(-5625 4675);
WIRE 17 -1 (-5625 4575)(-5625 4625);
WIRE 17 -1 (-5625 4675)(-5625 4775);
WIRE 17 -1 (-5625 4775)(-6375 4775);
FORCEPROP 2 LAST SIG_NAME M_E_DQ<63:0>
J 0
(-6325 4785);
DISPLAY 0.617021 (-6325 4785);
PAINT ORANGE (-6325 4785);
WIRE 17 -1 (-5625 4525)(-5625 4575);
WIRE 17 -1 (-5625 4475)(-5625 4525);
WIRE 17 -1 (-5625 4425)(-5625 4475);
WIRE 17 -1 (-5625 4375)(-5625 4425);
WIRE 17 -1 (-5625 4325)(-5625 4375);
WIRE 17 -1 (-5625 4275)(-5625 4325);
WIRE 17 -1 (-5625 4225)(-5625 4275);
WIRE 17 -1 (-5625 4175)(-5625 4225);
WIRE 17 -1 (-5625 4125)(-5625 4175);
WIRE 17 -1 (-5625 4075)(-5625 4125);
WIRE 17 -1 (-5625 4025)(-5625 4075);
WIRE 17 -1 (-5625 3975)(-5625 4025);
WIRE 17 -1 (-5625 3925)(-5625 3975);
WIRE 17 -1 (-5625 3875)(-5625 3925);
WIRE 17 -1 (-5625 3825)(-5625 3875);
WIRE 17 -1 (-5625 3775)(-5625 3825);
WIRE 17 -1 (-5625 3725)(-5625 3775);
WIRE 17 -1 (-5625 3675)(-5625 3725);
WIRE 17 -1 (-5625 3625)(-5625 3675);
WIRE 17 -1 (-5625 3575)(-5625 3625);
WIRE 17 -1 (-5625 3525)(-5625 3575);
WIRE 17 -1 (-5625 3475)(-5625 3525);
WIRE 17 -1 (-5625 3425)(-5625 3475);
WIRE 17 -1 (-5625 3375)(-5625 3425);
WIRE 17 -1 (-5625 3325)(-5625 3375);
WIRE 17 -1 (-5625 3275)(-5625 3325);
WIRE 17 -1 (-5625 3225)(-5625 3275);
WIRE 17 -1 (-5625 3175)(-5625 3225);
WIRE 17 -1 (-5625 3125)(-5625 3175);
WIRE 17 -1 (-5625 3075)(-5625 3125);
WIRE 17 -1 (-5625 3025)(-5625 3075);
WIRE 17 -1 (-5625 2975)(-5625 3025);
WIRE 17 -1 (-5625 2925)(-5625 2975);
WIRE 17 -1 (-5625 2875)(-5625 2925);
WIRE 17 -1 (-5625 2825)(-5625 2875);
WIRE 17 -1 (-5625 2775)(-5625 2825);
WIRE 17 -1 (-5625 2725)(-5625 2775);
WIRE 17 -1 (-5625 2675)(-5625 2725);
WIRE 17 -1 (-5625 2625)(-5625 2675);
WIRE 17 -1 (-5625 2575)(-5625 2625);
WIRE 17 -1 (-5625 2525)(-5625 2575);
WIRE 17 -1 (-5625 2475)(-5625 2525);
WIRE 17 -1 (-5625 2425)(-5625 2475);
WIRE 17 -1 (-5625 2375)(-5625 2425);
WIRE 17 -1 (-5625 2325)(-5625 2375);
WIRE 17 -1 (-5625 2275)(-5625 2325);
WIRE 17 -1 (-5625 2225)(-5625 2275);
WIRE 17 -1 (-5625 2175)(-5625 2225);
WIRE 17 -1 (-5625 2125)(-5625 2175);
WIRE 17 -1 (-5625 2075)(-5625 2125);
WIRE 17 -1 (-5625 2025)(-5625 2075);
WIRE 17 -1 (-5625 1975)(-5625 2025);
WIRE 17 -1 (-5625 1925)(-5625 1975);
WIRE 17 -1 (-5625 1875)(-5625 1925);
WIRE 17 -1 (-5625 1825)(-5625 1875);
WIRE 17 -1 (-5625 1775)(-5625 1825);
WIRE 17 -1 (-5625 1725)(-5625 1775);
WIRE 17 -1 (-5625 1675)(-5625 1725);
WIRE 17 -1 (-5625 1625)(-5625 1675);
WIRE 17 -1 (-5625 1575)(-5625 1625);
WIRE 17 -1 (-5625 1525)(-5625 1575);
WIRE 17 -1 (-5625 725)(-5625 775);
WIRE 17 -1 (-5625 675)(-5625 725);
WIRE 17 -1 (-5625 775)(-5625 800);
WIRE 17 -1 (-5625 800)(-6375 800);
FORCEPROP 2 LAST SIG_NAME M_E_CLK_DN<3:0>
J 0
(-6325 810);
DISPLAY 0.617021 (-6325 810);
PAINT ORANGE (-6325 810);
WIRE 17 -1 (-5625 625)(-5625 675);
WIRE 17 -1 (-5625 925)(-5625 975);
WIRE 17 -1 (-5625 875)(-5625 925);
WIRE 17 -1 (-5625 975)(-5625 1000);
WIRE 17 -1 (-5625 1000)(-6375 1000);
FORCEPROP 2 LAST SIG_NAME M_E_CLK_DP<3:0>
J 0
(-6325 1010);
DISPLAY 0.617021 (-6325 1010);
PAINT ORANGE (-6325 1010);
WIRE 17 -1 (-5625 825)(-5625 875);
WIRE 17 -1 (-5625 1375)(-5625 1425);
WIRE 17 -1 (-5625 1325)(-5625 1375);
WIRE 17 -1 (-5625 1425)(-5625 1450);
WIRE 17 -1 (-5625 1450)(-6375 1450);
FORCEPROP 2 LAST SIG_NAME M_E_ECC<7:0>
J 0
(-6325 1460);
DISPLAY 0.617021 (-6325 1460);
PAINT ORANGE (-6325 1460);
WIRE 17 -1 (-5625 1275)(-5625 1325);
WIRE 17 -1 (-5625 1225)(-5625 1275);
WIRE 17 -1 (-5625 1175)(-5625 1225);
WIRE 17 -1 (-5625 1125)(-5625 1175);
WIRE 17 -1 (-5625 1075)(-5625 1125);
WIRE 16 -1 (-5525 1750)(-5025 1750);
WIRE 16 -1 (-6400 500)(-5025 500);
FORCEPROP 2 LAST SIG_NAME M_E_C<2>
J 0
(-6350 510);
DISPLAY 0.617021 (-6350 510);
PAINT ORANGE (-6350 510);
WIRE 16 -1 (-5025 1050)(-5525 1050);
WIRE 16 -1 (-5025 1100)(-5525 1100);
WIRE 16 -1 (-5025 1150)(-5525 1150);
WIRE 16 -1 (-5025 1200)(-5525 1200);
WIRE 16 -1 (-5025 1250)(-5525 1250);
WIRE 16 -1 (-5025 1300)(-5525 1300);
WIRE 16 -1 (-5025 1350)(-5525 1350);
WIRE 16 -1 (-5025 1400)(-5525 1400);
WIRE 16 -1 (-5525 1500)(-5025 1500);
WIRE 16 -1 (-5525 1550)(-5025 1550);
WIRE 16 -1 (-5525 1600)(-5025 1600);
WIRE 16 -1 (-5025 1650)(-5525 1650);
WIRE 16 -1 (-5525 1700)(-5025 1700);
WIRE 16 -1 (-5025 1800)(-5525 1800);
WIRE 16 -1 (-5525 1850)(-5025 1850);
WIRE 16 -1 (-5525 1900)(-5025 1900);
WIRE 16 -1 (-5525 1950)(-5025 1950);
WIRE 16 -1 (-5525 2000)(-5025 2000);
WIRE 16 -1 (-5025 800)(-5525 800);
WIRE 16 -1 (-5025 850)(-5525 850);
WIRE 16 -1 (-5025 900)(-5525 900);
WIRE 16 -1 (-5025 950)(-5525 950);
WIRE 16 -1 (-5025 600)(-5525 600);
WIRE 16 -1 (-5025 650)(-5525 650);
WIRE 16 -1 (-5025 700)(-5525 700);
WIRE 16 -1 (-5025 750)(-5525 750);
WIRE 16 -1 (-5525 2050)(-5025 2050);
WIRE 16 -1 (-5525 2100)(-5025 2100);
WIRE 16 -1 (-5525 2150)(-5025 2150);
WIRE 16 -1 (-5525 2200)(-5025 2200);
WIRE 16 -1 (-5025 2250)(-5525 2250);
WIRE 16 -1 (-5525 2300)(-5025 2300);
WIRE 16 -1 (-5525 2350)(-5025 2350);
WIRE 16 -1 (-5025 2400)(-5525 2400);
WIRE 16 -1 (-5525 2450)(-5025 2450);
WIRE 16 -1 (-5525 2500)(-5025 2500);
WIRE 16 -1 (-5525 2550)(-5025 2550);
WIRE 16 -1 (-5525 2600)(-5025 2600);
WIRE 16 -1 (-5025 2650)(-5525 2650);
WIRE 16 -1 (-5525 2700)(-5025 2700);
WIRE 16 -1 (-5525 2750)(-5025 2750);
WIRE 16 -1 (-5525 2800)(-5025 2800);
WIRE 16 -1 (-5525 2850)(-5025 2850);
WIRE 16 -1 (-5525 2900)(-5025 2900);
WIRE 16 -1 (-5525 2950)(-5025 2950);
WIRE 16 -1 (-5025 3000)(-5525 3000);
WIRE 16 -1 (-5525 3050)(-5025 3050);
WIRE 16 -1 (-5525 3100)(-5025 3100);
WIRE 16 -1 (-5525 3150)(-5025 3150);
WIRE 16 -1 (-5525 3200)(-5025 3200);
WIRE 16 -1 (-5525 3250)(-5025 3250);
WIRE 16 -1 (-5525 3300)(-5025 3300);
WIRE 16 -1 (-5025 3350)(-5525 3350);
WIRE 16 -1 (-5525 3400)(-5025 3400);
WIRE 16 -1 (-5525 3450)(-5025 3450);
WIRE 16 -1 (-5025 3500)(-5525 3500);
WIRE 16 -1 (-5525 3550)(-5025 3550);
WIRE 16 -1 (-5525 3600)(-5025 3600);
WIRE 16 -1 (-5025 3650)(-5525 3650);
WIRE 16 -1 (-5025 3700)(-5525 3700);
WIRE 16 -1 (-5025 3750)(-5525 3750);
WIRE 16 -1 (-5025 3800)(-5525 3800);
WIRE 16 -1 (-5025 3850)(-5525 3850);
WIRE 16 -1 (-5025 3900)(-5525 3900);
WIRE 16 -1 (-5025 3950)(-5525 3950);
WIRE 16 -1 (-5025 4000)(-5525 4000);
WIRE 16 -1 (-5025 4050)(-5525 4050);
WIRE 16 -1 (-5025 4100)(-5525 4100);
WIRE 16 -1 (-5025 4150)(-5525 4150);
WIRE 16 -1 (-5025 4200)(-5525 4200);
WIRE 16 -1 (-5025 4250)(-5525 4250);
WIRE 16 -1 (-5025 4300)(-5525 4300);
WIRE 16 -1 (-5025 4350)(-5525 4350);
WIRE 16 -1 (-5025 4400)(-5525 4400);
WIRE 16 -1 (-5025 4450)(-5525 4450);
WIRE 16 -1 (-5025 4500)(-5525 4500);
WIRE 16 -1 (-5025 4550)(-5525 4550);
WIRE 16 -1 (-5025 4600)(-5525 4600);
WIRE 16 -1 (-5025 4650)(-5525 4650);
WIRE 16 -1 (-3325 1400)(-2900 1400);
WIRE 16 -1 (-3325 1450)(-2900 1450);
WIRE 16 -1 (-3325 1500)(-2900 1500);
WIRE 16 -1 (-3325 1550)(-2900 1550);
WIRE 16 -1 (-3325 1900)(-2900 1900);
WIRE 16 -1 (-3325 1950)(-2900 1950);
WIRE 16 -1 (-3325 2000)(-2900 2000);
WIRE 16 -1 (-3325 950)(-2900 950);
WIRE 16 -1 (-3325 1000)(-2900 1000);
WIRE 16 -1 (-3325 1050)(-2900 1050);
WIRE 16 -1 (-3325 1100)(-2900 1100);
WIRE 16 -1 (-3325 1150)(-2900 1150);
WIRE 16 -1 (-3325 1200)(-2900 1200);
WIRE 16 -1 (-3325 1250)(-2900 1250);
WIRE 16 -1 (-3325 1300)(-2900 1300);
WIRE 16 -1 (-3325 1650)(-2900 1650);
WIRE 16 -1 (-3325 1700)(-2900 1700);
WIRE 16 -1 (-3325 1750)(-2900 1750);
WIRE 16 -1 (-3325 1800)(-2900 1800);
WIRE 16 -1 (-3325 800)(-2900 800);
WIRE 16 -1 (-3325 850)(-2900 850);
WIRE 16 -1 (-3325 700)(-2900 700);
WIRE 16 -1 (-3325 750)(-2900 750);
WIRE 16 -1 (-3325 550)(-2050 550);
FORCEPROP 2 LAST SIG_NAME M_E_ALERT_N
J 0
(-2700 560);
DISPLAY 0.617021 (-2700 560);
PAINT ORANGE (-2700 560);
WIRE 16 -1 (-3325 500)(-2050 500);
FORCEPROP 2 LAST SIG_NAME M_E_PAR
J 0
(-2700 510);
DISPLAY 0.617021 (-2700 510);
PAINT ORANGE (-2700 510);
WIRE 16 -1 (-3325 600)(-2050 600);
FORCEPROP 2 LAST SIG_NAME M_E_ACT_N
J 0
(-2700 610);
DISPLAY 0.617021 (-2700 610);
PAINT ORANGE (-2700 610);
WIRE 16 -1 (-3325 2050)(-2900 2050);
WIRE 16 -1 (-3325 2100)(-2900 2100);
WIRE 16 -1 (-3325 2150)(-2900 2150);
WIRE 16 -1 (-3325 2200)(-2900 2200);
WIRE 16 -1 (-3325 2250)(-2900 2250);
WIRE 16 -1 (-3325 2300)(-2900 2300);
WIRE 16 -1 (-3325 2350)(-2900 2350);
WIRE 16 -1 (-3325 2400)(-2900 2400);
WIRE 16 -1 (-3325 2450)(-2900 2450);
WIRE 16 -1 (-3325 2500)(-2900 2500);
WIRE 16 -1 (-3325 2550)(-2900 2550);
WIRE 16 -1 (-3325 2600)(-2900 2600);
WIRE 16 -1 (-3325 2650)(-2900 2650);
WIRE 16 -1 (-3325 2700)(-2900 2700);
WIRE 16 -1 (-3325 2750)(-2900 2750);
WIRE 16 -1 (-3325 3800)(-2900 3800);
WIRE 16 -1 (-3325 3850)(-2900 3850);
WIRE 16 -1 (-3325 3900)(-2900 3900);
WIRE 16 -1 (-3325 3950)(-2900 3950);
WIRE 16 -1 (-3325 4000)(-2900 4000);
WIRE 16 -1 (-3325 4050)(-2900 4050);
WIRE 16 -1 (-3325 2850)(-2900 2850);
WIRE 16 -1 (-3325 2900)(-2900 2900);
WIRE 16 -1 (-3325 2950)(-2900 2950);
WIRE 16 -1 (-3325 3000)(-2900 3000);
WIRE 16 -1 (-3325 3050)(-2900 3050);
WIRE 16 -1 (-3325 3100)(-2900 3100);
WIRE 16 -1 (-3325 3150)(-2900 3150);
WIRE 16 -1 (-3325 3200)(-2900 3200);
WIRE 16 -1 (-3325 3250)(-2900 3250);
WIRE 16 -1 (-3325 3300)(-2900 3300);
WIRE 16 -1 (-3325 3350)(-2900 3350);
WIRE 16 -1 (-3325 3400)(-2900 3400);
WIRE 16 -1 (-3325 3450)(-2900 3450);
WIRE 16 -1 (-3325 3500)(-2900 3500);
WIRE 16 -1 (-3325 3550)(-2900 3550);
WIRE 16 -1 (-3325 3600)(-2900 3600);
WIRE 16 -1 (-3325 3650)(-2900 3650);
WIRE 16 -1 (-3325 3700)(-2900 3700);
WIRE 16 -1 (-3325 4100)(-2900 4100);
WIRE 16 -1 (-3325 4150)(-2900 4150);
WIRE 16 -1 (-3325 4200)(-2900 4200);
WIRE 16 -1 (-3325 4250)(-2900 4250);
WIRE 16 -1 (-3325 4300)(-2900 4300);
WIRE 16 -1 (-3325 4350)(-2900 4350);
WIRE 16 -1 (-3325 4400)(-2900 4400);
WIRE 16 -1 (-3325 4450)(-2900 4450);
WIRE 16 -1 (-3325 4500)(-2900 4500);
WIRE 16 -1 (-3325 4550)(-2900 4550);
WIRE 16 -1 (-3325 4600)(-2900 4600);
WIRE 16 -1 (-3325 4650)(-2900 4650);
FORCENOTE
ROOM=CPU0
(-7925 350) 0;
DISPLAY LEFT (-7925 350);
DISPLAY 1.382979 (-7925 350);
PAINT PURPLE (-7925 350);
FORCENOTE
BOM_COST=PROC_SOCKET
(-7925 225) 0;
DISPLAY LEFT (-7925 225);
DISPLAY 1.382979 (-7925 225);
PAINT PURPLE (-7925 225);
FORCENOTE
. 
(50 50) 0;
DISPLAY LEFT (50 50);
DISPLAY 1.021277 (50 50);
PAINT PURPLE (50 50);
QUIT
